FILE_TYPE = MACRO_DRAWING;
SET COLOR_WIRE YELLOW;
SET COLOR_PROP ORANGE;
SET COLOR_DOT WHITE;
SET COLOR_ARC YELLOW;
SET COLOR_BODY GREEN;
SET COLOR_NOTE PURPLE;
SET PROP_DISPLAY VALUE;
SET PAGE_NUMBER P103;
FORCEADD UNIVERSAL_GND..1
(-2675 -475);
FORCEPROP 3 LASTPIN (-2675 -425) SIG_NAME GND\g
J 0
(-2665 -415);
DISPLAY 0.659574 (-2665 -415);
PAINT MONO (-2665 -415);
DISPLAY INVISIBLE (-2665 -415);
FORCEPROP 1 LAST PATH I1
J 0
(-2600 -475);
DISPLAY 0.872340 (-2600 -475);
PAINT AQUA (-2600 -475);
DISPLAY INVISIBLE (-2600 -475);
FORCEPROP 1 LAST HDL_POWER GND
J 1
(-2650 -550);
DISPLAY 0.872340 (-2650 -550);
PAINT GREEN (-2650 -550);
DISPLAY INVISIBLE (-2650 -550);
FORCEPROP 2 LAST CDS_LIB logical_power
J 0
(-2675 -475);
PAINT MONO (-2675 -475);
DISPLAY INVISIBLE (-2675 -475);
FORCEADD OFFPAGE..1
(-3825 1550);
FORCEPROP 2 LAST $XR1 102 
J 0
(-4166 1550);
DISPLAY 0.638298 (-4166 1550);
PAINT MONO (-4166 1550);
FORCEPROP 2 LAST $XR0 53 
J 0
(-4046 1550);
DISPLAY 0.638298 (-4046 1550);
PAINT MONO (-4046 1550);
FORCEPROP 2 LAST CDS_LIB standard
J 0
(-3825 1550);
PAINT MONO (-3825 1550);
DISPLAY INVISIBLE (-3825 1550);
FORCEPROP 1 LAST OFFPAGE TRUE
J 0
(-3500 1425);
DISPLAY 0.872340 (-3500 1425);
DISPLAY INVISIBLE (-3500 1425);
FORCEPROP 1 LAST COMMENT_BODY TRUE
J 0
(-3700 1450);
DISPLAY 0.872340 (-3700 1450);
PAINT GREEN (-3700 1450);
DISPLAY INVISIBLE (-3700 1450);
FORCEPROP 2 LAST PATH I10
J 0
(-3775 1625);
DISPLAY 1.021277 (-3775 1625);
DISPLAY INVISIBLE (-3775 1625);
FORCEADD TAP..1
(-1250 3100);
FORCEPROP 3 LASTPIN (-1300 3100) SIG_NAME M_C_CPU1_SA_DQ<15>
J 0
(-1290 3110);
DISPLAY 0.659574 (-1290 3110);
PAINT MONO (-1290 3110);
DISPLAY INVISIBLE (-1290 3110);
FORCEPROP 1 LASTPIN (-1300 3100) BN 15
J 0
(-1312 3108);
DISPLAY 0.680851 (-1312 3108);
PAINT GREEN (-1312 3108);
FORCEPROP 2 LAST CDS_LIB standard
J 0
(-1250 3100);
PAINT MONO (-1250 3100);
DISPLAY INVISIBLE (-1250 3100);
FORCEPROP 1 LAST BODY_TYPE PLUMBING
J 0
(-1250 3150);
DISPLAY 0.872340 (-1250 3150);
PAINT GREEN (-1250 3150);
DISPLAY INVISIBLE (-1250 3150);
FORCEPROP 1 LAST HDL_TAP TRUE
J 0
(-925 2975);
DISPLAY 0.872340 (-925 2975);
DISPLAY INVISIBLE (-925 2975);
FORCEPROP 1 LAST PATH I100
J 0
(-1252 3100);
DISPLAY 0.872340 (-1252 3100);
PAINT GREEN (-1252 3100);
DISPLAY INVISIBLE (-1252 3100);
FORCEADD TAP..1
(-1250 3200);
FORCEPROP 3 LASTPIN (-1300 3200) SIG_NAME M_C_CPU1_SA_DQ<17>
J 0
(-1290 3210);
DISPLAY 0.659574 (-1290 3210);
PAINT MONO (-1290 3210);
DISPLAY INVISIBLE (-1290 3210);
FORCEPROP 1 LASTPIN (-1300 3200) BN 17
J 0
(-1312 3208);
DISPLAY 0.680851 (-1312 3208);
PAINT GREEN (-1312 3208);
FORCEPROP 2 LAST CDS_LIB standard
J 0
(-1250 3200);
PAINT MONO (-1250 3200);
DISPLAY INVISIBLE (-1250 3200);
FORCEPROP 1 LAST BODY_TYPE PLUMBING
J 0
(-1250 3250);
DISPLAY 0.872340 (-1250 3250);
PAINT GREEN (-1250 3250);
DISPLAY INVISIBLE (-1250 3250);
FORCEPROP 1 LAST HDL_TAP TRUE
J 0
(-925 3075);
DISPLAY 0.872340 (-925 3075);
DISPLAY INVISIBLE (-925 3075);
FORCEPROP 1 LAST PATH I101
J 0
(-1252 3200);
DISPLAY 0.872340 (-1252 3200);
PAINT GREEN (-1252 3200);
DISPLAY INVISIBLE (-1252 3200);
FORCEADD TAP..1
(-1250 3250);
FORCEPROP 3 LASTPIN (-1300 3250) SIG_NAME M_C_CPU1_SA_DQ<18>
J 0
(-1290 3260);
DISPLAY 0.659574 (-1290 3260);
PAINT MONO (-1290 3260);
DISPLAY INVISIBLE (-1290 3260);
FORCEPROP 1 LASTPIN (-1300 3250) BN 18
J 0
(-1312 3258);
DISPLAY 0.680851 (-1312 3258);
PAINT GREEN (-1312 3258);
FORCEPROP 2 LAST CDS_LIB standard
J 0
(-1250 3250);
PAINT MONO (-1250 3250);
DISPLAY INVISIBLE (-1250 3250);
FORCEPROP 1 LAST BODY_TYPE PLUMBING
J 0
(-1250 3300);
DISPLAY 0.872340 (-1250 3300);
PAINT GREEN (-1250 3300);
DISPLAY INVISIBLE (-1250 3300);
FORCEPROP 1 LAST HDL_TAP TRUE
J 0
(-925 3125);
DISPLAY 0.872340 (-925 3125);
DISPLAY INVISIBLE (-925 3125);
FORCEPROP 1 LAST PATH I102
J 0
(-1252 3250);
DISPLAY 0.872340 (-1252 3250);
PAINT GREEN (-1252 3250);
DISPLAY INVISIBLE (-1252 3250);
FORCEADD TAP..1
(-1250 3300);
FORCEPROP 3 LASTPIN (-1300 3300) SIG_NAME M_C_CPU1_SA_DQ<19>
J 0
(-1290 3310);
DISPLAY 0.659574 (-1290 3310);
PAINT MONO (-1290 3310);
DISPLAY INVISIBLE (-1290 3310);
FORCEPROP 1 LASTPIN (-1300 3300) BN 19
J 0
(-1312 3308);
DISPLAY 0.680851 (-1312 3308);
PAINT GREEN (-1312 3308);
FORCEPROP 2 LAST CDS_LIB standard
J 0
(-1250 3300);
PAINT MONO (-1250 3300);
DISPLAY INVISIBLE (-1250 3300);
FORCEPROP 1 LAST BODY_TYPE PLUMBING
J 0
(-1250 3350);
DISPLAY 0.872340 (-1250 3350);
PAINT GREEN (-1250 3350);
DISPLAY INVISIBLE (-1250 3350);
FORCEPROP 1 LAST HDL_TAP TRUE
J 0
(-925 3175);
DISPLAY 0.872340 (-925 3175);
DISPLAY INVISIBLE (-925 3175);
FORCEPROP 1 LAST PATH I103
J 0
(-1252 3300);
DISPLAY 0.872340 (-1252 3300);
PAINT GREEN (-1252 3300);
DISPLAY INVISIBLE (-1252 3300);
FORCEADD TAP..1
(-1250 3350);
FORCEPROP 3 LASTPIN (-1300 3350) SIG_NAME M_C_CPU1_SA_DQ<20>
J 0
(-1290 3360);
DISPLAY 0.659574 (-1290 3360);
PAINT MONO (-1290 3360);
DISPLAY INVISIBLE (-1290 3360);
FORCEPROP 1 LASTPIN (-1300 3350) BN 20
J 0
(-1312 3358);
DISPLAY 0.680851 (-1312 3358);
PAINT GREEN (-1312 3358);
FORCEPROP 2 LAST CDS_LIB standard
J 0
(-1250 3350);
PAINT MONO (-1250 3350);
DISPLAY INVISIBLE (-1250 3350);
FORCEPROP 1 LAST BODY_TYPE PLUMBING
J 0
(-1250 3400);
DISPLAY 0.872340 (-1250 3400);
PAINT GREEN (-1250 3400);
DISPLAY INVISIBLE (-1250 3400);
FORCEPROP 1 LAST HDL_TAP TRUE
J 0
(-925 3225);
DISPLAY 0.872340 (-925 3225);
DISPLAY INVISIBLE (-925 3225);
FORCEPROP 1 LAST PATH I104
J 0
(-1252 3350);
DISPLAY 0.872340 (-1252 3350);
PAINT GREEN (-1252 3350);
DISPLAY INVISIBLE (-1252 3350);
FORCEADD TAP..1
(-1250 3400);
FORCEPROP 3 LASTPIN (-1300 3400) SIG_NAME M_C_CPU1_SA_DQ<21>
J 0
(-1290 3410);
DISPLAY 0.659574 (-1290 3410);
PAINT MONO (-1290 3410);
DISPLAY INVISIBLE (-1290 3410);
FORCEPROP 1 LASTPIN (-1300 3400) BN 21
J 0
(-1312 3408);
DISPLAY 0.680851 (-1312 3408);
PAINT GREEN (-1312 3408);
FORCEPROP 2 LAST CDS_LIB standard
J 0
(-1250 3400);
PAINT MONO (-1250 3400);
DISPLAY INVISIBLE (-1250 3400);
FORCEPROP 1 LAST BODY_TYPE PLUMBING
J 0
(-1250 3450);
DISPLAY 0.872340 (-1250 3450);
PAINT GREEN (-1250 3450);
DISPLAY INVISIBLE (-1250 3450);
FORCEPROP 1 LAST HDL_TAP TRUE
J 0
(-925 3275);
DISPLAY 0.872340 (-925 3275);
DISPLAY INVISIBLE (-925 3275);
FORCEPROP 1 LAST PATH I105
J 0
(-1252 3400);
DISPLAY 0.872340 (-1252 3400);
PAINT GREEN (-1252 3400);
DISPLAY INVISIBLE (-1252 3400);
FORCEADD TAP..1
(-1250 3450);
FORCEPROP 3 LASTPIN (-1300 3450) SIG_NAME M_C_CPU1_SA_DQ<22>
J 0
(-1290 3460);
DISPLAY 0.659574 (-1290 3460);
PAINT MONO (-1290 3460);
DISPLAY INVISIBLE (-1290 3460);
FORCEPROP 1 LASTPIN (-1300 3450) BN 22
J 0
(-1312 3458);
DISPLAY 0.680851 (-1312 3458);
PAINT GREEN (-1312 3458);
FORCEPROP 2 LAST CDS_LIB standard
J 0
(-1250 3450);
DISPLAY INVISIBLE (-1250 3450);
FORCEPROP 1 LAST BODY_TYPE PLUMBING
J 0
(-1250 3500);
DISPLAY 0.872340 (-1250 3500);
PAINT GREEN (-1250 3500);
DISPLAY INVISIBLE (-1250 3500);
FORCEPROP 1 LAST HDL_TAP TRUE
J 0
(-925 3325);
DISPLAY 0.872340 (-925 3325);
DISPLAY INVISIBLE (-925 3325);
FORCEPROP 1 LAST PATH I106
J 0
(-1252 3450);
DISPLAY 0.872340 (-1252 3450);
PAINT GREEN (-1252 3450);
DISPLAY INVISIBLE (-1252 3450);
FORCEADD TAP..1
(-1250 3500);
FORCEPROP 3 LASTPIN (-1300 3500) SIG_NAME M_C_CPU1_SA_DQ<23>
J 0
(-1290 3510);
DISPLAY 0.659574 (-1290 3510);
PAINT MONO (-1290 3510);
DISPLAY INVISIBLE (-1290 3510);
FORCEPROP 1 LASTPIN (-1300 3500) BN 23
J 0
(-1312 3508);
DISPLAY 0.680851 (-1312 3508);
PAINT GREEN (-1312 3508);
FORCEPROP 2 LAST CDS_LIB standard
J 0
(-1250 3500);
DISPLAY INVISIBLE (-1250 3500);
FORCEPROP 1 LAST BODY_TYPE PLUMBING
J 0
(-1250 3550);
DISPLAY 0.872340 (-1250 3550);
PAINT GREEN (-1250 3550);
DISPLAY INVISIBLE (-1250 3550);
FORCEPROP 1 LAST HDL_TAP TRUE
J 0
(-925 3375);
DISPLAY 0.872340 (-925 3375);
DISPLAY INVISIBLE (-925 3375);
FORCEPROP 1 LAST PATH I107
J 0
(-1252 3500);
DISPLAY 0.872340 (-1252 3500);
PAINT GREEN (-1252 3500);
DISPLAY INVISIBLE (-1252 3500);
FORCEADD TAP..1
(-1250 3600);
FORCEPROP 3 LASTPIN (-1300 3600) SIG_NAME M_C_CPU1_SA_DQ<25>
J 0
(-1290 3610);
DISPLAY 0.659574 (-1290 3610);
PAINT MONO (-1290 3610);
DISPLAY INVISIBLE (-1290 3610);
FORCEPROP 1 LASTPIN (-1300 3600) BN 25
J 0
(-1312 3608);
DISPLAY 0.680851 (-1312 3608);
PAINT GREEN (-1312 3608);
FORCEPROP 2 LAST CDS_LIB standard
J 0
(-1250 3600);
DISPLAY INVISIBLE (-1250 3600);
FORCEPROP 1 LAST BODY_TYPE PLUMBING
J 0
(-1250 3650);
DISPLAY 0.872340 (-1250 3650);
PAINT GREEN (-1250 3650);
DISPLAY INVISIBLE (-1250 3650);
FORCEPROP 1 LAST HDL_TAP TRUE
J 0
(-925 3475);
DISPLAY 0.872340 (-925 3475);
DISPLAY INVISIBLE (-925 3475);
FORCEPROP 1 LAST PATH I108
J 0
(-1252 3600);
DISPLAY 0.872340 (-1252 3600);
PAINT GREEN (-1252 3600);
DISPLAY INVISIBLE (-1252 3600);
FORCEADD TAP..1
(-1250 3550);
FORCEPROP 3 LASTPIN (-1300 3550) SIG_NAME M_C_CPU1_SA_DQ<24>
J 0
(-1290 3560);
DISPLAY 0.659574 (-1290 3560);
PAINT MONO (-1290 3560);
DISPLAY INVISIBLE (-1290 3560);
FORCEPROP 1 LASTPIN (-1300 3550) BN 24
J 0
(-1312 3558);
DISPLAY 0.680851 (-1312 3558);
PAINT GREEN (-1312 3558);
FORCEPROP 2 LAST CDS_LIB standard
J 0
(-1250 3550);
DISPLAY INVISIBLE (-1250 3550);
FORCEPROP 1 LAST BODY_TYPE PLUMBING
J 0
(-1250 3600);
DISPLAY 0.872340 (-1250 3600);
PAINT GREEN (-1250 3600);
DISPLAY INVISIBLE (-1250 3600);
FORCEPROP 1 LAST HDL_TAP TRUE
J 0
(-925 3425);
DISPLAY 0.872340 (-925 3425);
DISPLAY INVISIBLE (-925 3425);
FORCEPROP 1 LAST PATH I109
J 0
(-1252 3550);
DISPLAY 0.872340 (-1252 3550);
PAINT GREEN (-1252 3550);
DISPLAY INVISIBLE (-1252 3550);
FORCEADD OFFPAGE..1
(-3825 1650);
FORCEPROP 2 LAST $XR3 105 
J 0
(-4197 1614);
DISPLAY 0.638298 (-4197 1614);
PAINT MONO (-4197 1614);
FORCEPROP 2 LAST $XR2 104 
J 0
(-4077 1614);
DISPLAY 0.638298 (-4077 1614);
PAINT MONO (-4077 1614);
FORCEPROP 2 LAST $XR1 102 
J 0
(-4197 1650);
DISPLAY 0.638298 (-4197 1650);
PAINT MONO (-4197 1650);
FORCEPROP 2 LAST $XR0 130 
J 0
(-4077 1650);
DISPLAY 0.638298 (-4077 1650);
PAINT MONO (-4077 1650);
FORCEPROP 2 LAST CDS_LIB standard
J 0
(-3825 1650);
PAINT MONO (-3825 1650);
DISPLAY INVISIBLE (-3825 1650);
FORCEPROP 1 LAST OFFPAGE TRUE
J 0
(-3500 1525);
DISPLAY 0.872340 (-3500 1525);
DISPLAY INVISIBLE (-3500 1525);
FORCEPROP 1 LAST COMMENT_BODY TRUE
J 0
(-3700 1550);
DISPLAY 0.872340 (-3700 1550);
PAINT GREEN (-3700 1550);
DISPLAY INVISIBLE (-3700 1550);
FORCEPROP 2 LAST PATH I11
J 0
(-3775 1725);
DISPLAY 1.021277 (-3775 1725);
DISPLAY INVISIBLE (-3775 1725);
FORCEADD TAP..1
(-1250 3650);
FORCEPROP 3 LASTPIN (-1300 3650) SIG_NAME M_C_CPU1_SA_DQ<26>
J 0
(-1290 3660);
DISPLAY 0.659574 (-1290 3660);
PAINT MONO (-1290 3660);
DISPLAY INVISIBLE (-1290 3660);
FORCEPROP 1 LASTPIN (-1300 3650) BN 26
J 0
(-1312 3658);
DISPLAY 0.680851 (-1312 3658);
PAINT GREEN (-1312 3658);
FORCEPROP 2 LAST CDS_LIB standard
J 0
(-1250 3650);
DISPLAY INVISIBLE (-1250 3650);
FORCEPROP 1 LAST BODY_TYPE PLUMBING
J 0
(-1250 3700);
DISPLAY 0.872340 (-1250 3700);
PAINT GREEN (-1250 3700);
DISPLAY INVISIBLE (-1250 3700);
FORCEPROP 1 LAST HDL_TAP TRUE
J 0
(-925 3525);
DISPLAY 0.872340 (-925 3525);
DISPLAY INVISIBLE (-925 3525);
FORCEPROP 1 LAST PATH I110
J 0
(-1252 3650);
DISPLAY 0.872340 (-1252 3650);
PAINT GREEN (-1252 3650);
DISPLAY INVISIBLE (-1252 3650);
FORCEADD TAP..1
(-1250 3700);
FORCEPROP 3 LASTPIN (-1300 3700) SIG_NAME M_C_CPU1_SA_DQ<27>
J 0
(-1290 3710);
DISPLAY 0.659574 (-1290 3710);
PAINT MONO (-1290 3710);
DISPLAY INVISIBLE (-1290 3710);
FORCEPROP 1 LASTPIN (-1300 3700) BN 27
J 0
(-1312 3708);
DISPLAY 0.680851 (-1312 3708);
PAINT GREEN (-1312 3708);
FORCEPROP 2 LAST CDS_LIB standard
J 0
(-1250 3700);
DISPLAY INVISIBLE (-1250 3700);
FORCEPROP 1 LAST BODY_TYPE PLUMBING
J 0
(-1250 3750);
DISPLAY 0.872340 (-1250 3750);
PAINT GREEN (-1250 3750);
DISPLAY INVISIBLE (-1250 3750);
FORCEPROP 1 LAST HDL_TAP TRUE
J 0
(-925 3575);
DISPLAY 0.872340 (-925 3575);
DISPLAY INVISIBLE (-925 3575);
FORCEPROP 1 LAST PATH I111
J 0
(-1252 3700);
DISPLAY 0.872340 (-1252 3700);
PAINT GREEN (-1252 3700);
DISPLAY INVISIBLE (-1252 3700);
FORCEADD TAP..1
(-1250 3750);
FORCEPROP 3 LASTPIN (-1300 3750) SIG_NAME M_C_CPU1_SA_DQ<28>
J 0
(-1290 3760);
DISPLAY 0.659574 (-1290 3760);
PAINT MONO (-1290 3760);
DISPLAY INVISIBLE (-1290 3760);
FORCEPROP 1 LASTPIN (-1300 3750) BN 28
J 0
(-1312 3758);
DISPLAY 0.680851 (-1312 3758);
PAINT GREEN (-1312 3758);
FORCEPROP 2 LAST CDS_LIB standard
J 0
(-1250 3750);
DISPLAY INVISIBLE (-1250 3750);
FORCEPROP 1 LAST BODY_TYPE PLUMBING
J 0
(-1250 3800);
DISPLAY 0.872340 (-1250 3800);
PAINT GREEN (-1250 3800);
DISPLAY INVISIBLE (-1250 3800);
FORCEPROP 1 LAST HDL_TAP TRUE
J 0
(-925 3625);
DISPLAY 0.872340 (-925 3625);
DISPLAY INVISIBLE (-925 3625);
FORCEPROP 1 LAST PATH I112
J 0
(-1252 3750);
DISPLAY 0.872340 (-1252 3750);
PAINT GREEN (-1252 3750);
DISPLAY INVISIBLE (-1252 3750);
FORCEADD OFFPAGE..1
(-3825 3925);
FORCEPROP 2 LAST $XR1 102 
J 0
(-4166 3925);
DISPLAY 0.638298 (-4166 3925);
PAINT MONO (-4166 3925);
FORCEPROP 2 LAST $XR0 53 
J 0
(-4046 3925);
DISPLAY 0.638298 (-4046 3925);
PAINT MONO (-4046 3925);
FORCEPROP 2 LAST CDS_LIB standard
J 0
(-3825 3925);
PAINT MONO (-3825 3925);
DISPLAY INVISIBLE (-3825 3925);
FORCEPROP 1 LAST OFFPAGE TRUE
J 0
(-3500 3800);
DISPLAY 0.872340 (-3500 3800);
DISPLAY INVISIBLE (-3500 3800);
FORCEPROP 1 LAST COMMENT_BODY TRUE
J 0
(-3700 3825);
DISPLAY 0.872340 (-3700 3825);
PAINT GREEN (-3700 3825);
DISPLAY INVISIBLE (-3700 3825);
FORCEPROP 2 LAST PATH I113
J 0
(-3775 4000);
DISPLAY 1.021277 (-3775 4000);
DISPLAY INVISIBLE (-3775 4000);
FORCEADD TAP..1
R 2
(-2900 3800);
FORCEPROP 3 LASTPIN (-2850 3800) SIG_NAME M_C_CPU1_SA_CA<4>
J 0
(-2840 3810);
DISPLAY 0.659574 (-2840 3810);
PAINT MONO (-2840 3810);
DISPLAY INVISIBLE (-2840 3810);
FORCEPROP 1 LASTPIN (-2850 3800) BN 4
J 2
(-2838 3808);
DISPLAY 0.680851 (-2838 3808);
PAINT GREEN (-2838 3808);
FORCEPROP 2 LAST CDS_LIB standard
J 0
(-2900 3800);
DISPLAY INVISIBLE (-2900 3800);
FORCEPROP 1 LAST BODY_TYPE PLUMBING
J 2
(-2900 3850);
DISPLAY 0.872340 (-2900 3850);
PAINT GREEN (-2900 3850);
DISPLAY INVISIBLE (-2900 3850);
FORCEPROP 1 LAST HDL_TAP TRUE
J 2
(-3225 3675);
DISPLAY 0.872340 (-3225 3675);
DISPLAY INVISIBLE (-3225 3675);
FORCEPROP 1 LAST PATH I114
J 2
(-2898 3800);
DISPLAY 0.872340 (-2898 3800);
PAINT GREEN (-2898 3800);
DISPLAY INVISIBLE (-2898 3800);
FORCEADD TAP..1
R 2
(-2900 3850);
FORCEPROP 3 LASTPIN (-2850 3850) SIG_NAME M_C_CPU1_SA_CA<5>
J 0
(-2840 3860);
DISPLAY 0.659574 (-2840 3860);
PAINT MONO (-2840 3860);
DISPLAY INVISIBLE (-2840 3860);
FORCEPROP 1 LASTPIN (-2850 3850) BN 5
J 2
(-2838 3858);
DISPLAY 0.680851 (-2838 3858);
PAINT GREEN (-2838 3858);
FORCEPROP 2 LAST CDS_LIB standard
J 0
(-2900 3850);
DISPLAY INVISIBLE (-2900 3850);
FORCEPROP 1 LAST BODY_TYPE PLUMBING
J 2
(-2900 3900);
DISPLAY 0.872340 (-2900 3900);
PAINT GREEN (-2900 3900);
DISPLAY INVISIBLE (-2900 3900);
FORCEPROP 1 LAST HDL_TAP TRUE
J 2
(-3225 3725);
DISPLAY 0.872340 (-3225 3725);
DISPLAY INVISIBLE (-3225 3725);
FORCEPROP 1 LAST PATH I115
J 2
(-2898 3850);
DISPLAY 0.872340 (-2898 3850);
PAINT GREEN (-2898 3850);
DISPLAY INVISIBLE (-2898 3850);
FORCEADD TAP..1
R 2
(-2900 3900);
FORCEPROP 3 LASTPIN (-2850 3900) SIG_NAME M_C_CPU1_SA_CA<6>
J 0
(-2840 3910);
DISPLAY 0.659574 (-2840 3910);
PAINT MONO (-2840 3910);
DISPLAY INVISIBLE (-2840 3910);
FORCEPROP 1 LASTPIN (-2850 3900) BN 6
J 2
(-2838 3908);
DISPLAY 0.680851 (-2838 3908);
PAINT GREEN (-2838 3908);
FORCEPROP 2 LAST CDS_LIB standard
J 0
(-2900 3900);
DISPLAY INVISIBLE (-2900 3900);
FORCEPROP 1 LAST BODY_TYPE PLUMBING
J 2
(-2900 3950);
DISPLAY 0.872340 (-2900 3950);
PAINT GREEN (-2900 3950);
DISPLAY INVISIBLE (-2900 3950);
FORCEPROP 1 LAST HDL_TAP TRUE
J 2
(-3225 3775);
DISPLAY 0.872340 (-3225 3775);
DISPLAY INVISIBLE (-3225 3775);
FORCEPROP 1 LAST PATH I116
J 2
(-2898 3900);
DISPLAY 0.872340 (-2898 3900);
PAINT GREEN (-2898 3900);
DISPLAY INVISIBLE (-2898 3900);
FORCEADD TAP..1
(-1250 3800);
FORCEPROP 3 LASTPIN (-1300 3800) SIG_NAME M_C_CPU1_SA_DQ<29>
J 0
(-1290 3810);
DISPLAY 0.659574 (-1290 3810);
PAINT MONO (-1290 3810);
DISPLAY INVISIBLE (-1290 3810);
FORCEPROP 1 LASTPIN (-1300 3800) BN 29
J 0
(-1312 3808);
DISPLAY 0.680851 (-1312 3808);
PAINT GREEN (-1312 3808);
FORCEPROP 2 LAST CDS_LIB standard
J 0
(-1250 3800);
DISPLAY INVISIBLE (-1250 3800);
FORCEPROP 1 LAST BODY_TYPE PLUMBING
J 0
(-1250 3850);
DISPLAY 0.872340 (-1250 3850);
PAINT GREEN (-1250 3850);
DISPLAY INVISIBLE (-1250 3850);
FORCEPROP 1 LAST HDL_TAP TRUE
J 0
(-925 3675);
DISPLAY 0.872340 (-925 3675);
DISPLAY INVISIBLE (-925 3675);
FORCEPROP 1 LAST PATH I117
J 0
(-1252 3800);
DISPLAY 0.872340 (-1252 3800);
PAINT GREEN (-1252 3800);
DISPLAY INVISIBLE (-1252 3800);
FORCEADD TAP..1
(-1250 3850);
FORCEPROP 3 LASTPIN (-1300 3850) SIG_NAME M_C_CPU1_SA_DQ<30>
J 0
(-1290 3860);
DISPLAY 0.659574 (-1290 3860);
PAINT MONO (-1290 3860);
DISPLAY INVISIBLE (-1290 3860);
FORCEPROP 1 LASTPIN (-1300 3850) BN 30
J 0
(-1312 3858);
DISPLAY 0.680851 (-1312 3858);
PAINT GREEN (-1312 3858);
FORCEPROP 2 LAST CDS_LIB standard
J 0
(-1250 3850);
DISPLAY INVISIBLE (-1250 3850);
FORCEPROP 1 LAST BODY_TYPE PLUMBING
J 0
(-1250 3900);
DISPLAY 0.872340 (-1250 3900);
PAINT GREEN (-1250 3900);
DISPLAY INVISIBLE (-1250 3900);
FORCEPROP 1 LAST HDL_TAP TRUE
J 0
(-925 3725);
DISPLAY 0.872340 (-925 3725);
DISPLAY INVISIBLE (-925 3725);
FORCEPROP 1 LAST PATH I118
J 0
(-1252 3850);
DISPLAY 0.872340 (-1252 3850);
PAINT GREEN (-1252 3850);
DISPLAY INVISIBLE (-1252 3850);
FORCEADD TAP..1
(-1250 3900);
FORCEPROP 3 LASTPIN (-1300 3900) SIG_NAME M_C_CPU1_SA_DQ<31>
J 0
(-1290 3910);
DISPLAY 0.659574 (-1290 3910);
PAINT MONO (-1290 3910);
DISPLAY INVISIBLE (-1290 3910);
FORCEPROP 1 LASTPIN (-1300 3900) BN 31
J 0
(-1312 3908);
DISPLAY 0.680851 (-1312 3908);
PAINT GREEN (-1312 3908);
FORCEPROP 2 LAST CDS_LIB standard
J 0
(-1250 3900);
DISPLAY INVISIBLE (-1250 3900);
FORCEPROP 1 LAST BODY_TYPE PLUMBING
J 0
(-1250 3950);
DISPLAY 0.872340 (-1250 3950);
PAINT GREEN (-1250 3950);
DISPLAY INVISIBLE (-1250 3950);
FORCEPROP 1 LAST HDL_TAP TRUE
J 0
(-925 3775);
DISPLAY 0.872340 (-925 3775);
DISPLAY INVISIBLE (-925 3775);
FORCEPROP 1 LAST PATH I119
J 0
(-1252 3900);
DISPLAY 0.872340 (-1252 3900);
PAINT GREEN (-1252 3900);
DISPLAY INVISIBLE (-1252 3900);
FORCEADD VCC_CORE..1
(-3725 1775);
FORCEPROP 3 LASTPIN (-3725 1725) SIG_NAME P3V3_AUX\g
J 0
(-3715 1735);
DISPLAY 0.659574 (-3715 1735);
PAINT MONO (-3715 1735);
DISPLAY INVISIBLE (-3715 1735);
FORCEPROP 1 LAST HDL_POWER P3V3_AUX
J 1
(-3725 1825);
DISPLAY 1.148936 (-3725 1825);
PAINT GREEN (-3725 1825);
FORCEPROP 2 LAST CDS_LIB logical_power
J 0
(-3725 1775);
PAINT MONO (-3725 1775);
DISPLAY INVISIBLE (-3725 1775);
FORCEPROP 1 LAST PATH I12
J 0
(-3675 1800);
DISPLAY 0.872340 (-3675 1800);
PAINT AQUA (-3675 1800);
DISPLAY INVISIBLE (-3675 1800);
FORCEADD UNIVERSAL_GND..1
(475 -350);
FORCEPROP 3 LASTPIN (475 -300) SIG_NAME GND\g
J 0
(485 -290);
DISPLAY 0.659574 (485 -290);
PAINT MONO (485 -290);
DISPLAY INVISIBLE (485 -290);
FORCEPROP 1 LAST PATH I120
J 0
(550 -350);
DISPLAY 0.872340 (550 -350);
PAINT AQUA (550 -350);
DISPLAY INVISIBLE (550 -350);
FORCEPROP 1 LAST HDL_POWER GND
J 1
(500 -425);
DISPLAY 0.872340 (500 -425);
PAINT GREEN (500 -425);
DISPLAY INVISIBLE (500 -425);
FORCEPROP 2 LAST CDS_LIB logical_power
J 0
(475 -350);
PAINT MONO (475 -350);
DISPLAY INVISIBLE (475 -350);
FORCEADD UNIVERSAL_GND..1
(2100 -350);
FORCEPROP 3 LASTPIN (2100 -300) SIG_NAME GND\g
J 0
(2110 -290);
DISPLAY 0.659574 (2110 -290);
PAINT MONO (2110 -290);
DISPLAY INVISIBLE (2110 -290);
FORCEPROP 1 LAST PATH I121
J 0
(2175 -350);
DISPLAY 0.872340 (2175 -350);
PAINT AQUA (2175 -350);
DISPLAY INVISIBLE (2175 -350);
FORCEPROP 1 LAST HDL_POWER GND
J 1
(2125 -425);
DISPLAY 0.872340 (2125 -425);
PAINT GREEN (2125 -425);
DISPLAY INVISIBLE (2125 -425);
FORCEPROP 2 LAST CDS_LIB logical_power
J 0
(2100 -350);
PAINT MONO (2100 -350);
DISPLAY INVISIBLE (2100 -350);
FORCEADD Q_CAP..1
(475 25);
FORCEPROP 1 LAST PART_NUMBER CH5221MEB00
J 0
(525 -125);
DISPLAY 0.978723 (525 -125);
DISPLAY INVISIBLE (525 -125);
FORCEPROP 1 LAST VOLTAGE 6.3V
J 0
(525 25);
DISPLAY 0.978723 (525 25);
FORCEPROP 1 LAST VALUE 2.2UF
J 0
(525 75);
DISPLAY 0.978723 (525 75);
FORCEPROP 1 LAST TOLERANCE 20%
J 0
(525 -25);
DISPLAY 0.978723 (525 -25);
FORCEPROP 1 LAST MATERIAL X6S
J 0
(525 -75);
DISPLAY 0.978723 (525 -75);
FORCEPROP 1 LAST PACK_TYPE C0402
J 0
(525 -175);
DISPLAY 0.978723 (525 -175);
FORCEPROP 1 LAST $LOCATION C65
J 0
(525 125);
DISPLAY 0.978723 (525 125);
FORCEPROP 1 LASTPIN (475 125) $PN 1
J 0
(485 105);
DISPLAY 0.787234 (485 105);
FORCEPROP 1 LASTPIN (475 -75) $PN 2
J 0
(485 -95);
DISPLAY 0.787234 (485 -95);
FORCEPROP 2 LAST CDS_LIB pure_quanta
J 0
(475 25);
PAINT MONO (475 25);
DISPLAY INVISIBLE (475 25);
FORCEPROP 1 LAST PATH I122
J 0
(525 175);
DISPLAY 0.978723 (525 175);
PAINT WHITE (525 175);
DISPLAY INVISIBLE (525 175);
FORCEPROP 1 LAST $LOCATION C65
J 0
(525 225);
DISPLAY 1.021277 (525 225);
DISPLAY INVISIBLE (525 225);
FORCEPROP 2 LAST CDS_LOCATION C65
J 0
(525 225);
DISPLAY 1.021277 (525 225);
DISPLAY INVISIBLE (525 225);
FORCEPROP 2 LAST $SEC 1
J 0
(525 225);
DISPLAY 0.680851 (525 225);
PAINT MONO (525 225);
DISPLAY INVISIBLE (525 225);
FORCEPROP 2 LAST CDS_SEC 1
J 0
(525 225);
DISPLAY 1.021277 (525 225);
DISPLAY INVISIBLE (525 225);
FORCEADD VCC_CORE..1
(475 350);
FORCEPROP 3 LASTPIN (475 300) SIG_NAME P3V3_AUX\g
J 0
(485 310);
DISPLAY 0.659574 (485 310);
PAINT MONO (485 310);
DISPLAY INVISIBLE (485 310);
FORCEPROP 1 LAST HDL_POWER P3V3_AUX
J 1
(475 400);
DISPLAY 1.148936 (475 400);
PAINT GREEN (475 400);
FORCEPROP 2 LAST CDS_LIB logical_power
J 0
(475 350);
PAINT MONO (475 350);
DISPLAY INVISIBLE (475 350);
FORCEPROP 1 LAST PATH I123
J 0
(525 375);
DISPLAY 0.872340 (525 375);
PAINT AQUA (525 375);
DISPLAY INVISIBLE (525 375);
FORCEADD OFFPAGE..3
(-425 2275);
FORCEPROP 2 LAST $XR1 102 
J 0
(-121 2275);
DISPLAY 0.638298 (-121 2275);
PAINT MONO (-121 2275);
FORCEPROP 2 LAST $XR0 53 
J 0
(-211 2275);
DISPLAY 0.638298 (-211 2275);
PAINT MONO (-211 2275);
FORCEPROP 2 LAST CDS_LIB standard
J 2
(-425 2275);
DISPLAY INVISIBLE (-425 2275);
FORCEPROP 1 LAST OFFPAGE TRUE
J 0
(-100 2150);
DISPLAY 0.872340 (-100 2150);
DISPLAY INVISIBLE (-100 2150);
FORCEPROP 1 LAST COMMENT_BODY TRUE
J 0
(-475 2175);
DISPLAY 0.872340 (-475 2175);
PAINT GREEN (-475 2175);
DISPLAY INVISIBLE (-475 2175);
FORCEPROP 2 LAST PATH I124
J 0
(-225 2350);
DISPLAY 1.021277 (-225 2350);
DISPLAY INVISIBLE (-225 2350);
FORCEADD Q_CAP..1
(1475 25);
FORCEPROP 1 LAST PART_NUMBER CH6103KEA00
J 0
(1525 -125);
DISPLAY 0.978723 (1525 -125);
DISPLAY INVISIBLE (1525 -125);
FORCEPROP 1 LAST TOLERANCE 10%
J 0
(1525 -25);
DISPLAY 0.978723 (1525 -25);
FORCEPROP 1 LAST PACK_TYPE C0805
J 0
(1525 -175);
DISPLAY 0.978723 (1525 -175);
FORCEPROP 1 LAST VOLTAGE 16V
J 0
(1525 25);
DISPLAY 0.978723 (1525 25);
FORCEPROP 1 LAST VALUE 10UF
J 0
(1525 75);
DISPLAY 0.978723 (1525 75);
FORCEPROP 1 LAST MATERIAL X6S
J 0
(1525 -75);
DISPLAY 0.978723 (1525 -75);
FORCEPROP 1 LAST $LOCATION C66
J 0
(1525 125);
DISPLAY 0.978723 (1525 125);
FORCEPROP 1 LASTPIN (1475 125) $PN 1
J 0
(1485 105);
DISPLAY 0.787234 (1485 105);
FORCEPROP 1 LASTPIN (1475 -75) $PN 2
J 0
(1485 -95);
DISPLAY 0.787234 (1485 -95);
FORCEPROP 2 LAST CDS_LIB pure_quanta
J 0
(1475 25);
PAINT MONO (1475 25);
DISPLAY INVISIBLE (1475 25);
FORCEPROP 1 LAST PATH I126
J 0
(1525 175);
DISPLAY 0.978723 (1525 175);
PAINT WHITE (1525 175);
DISPLAY INVISIBLE (1525 175);
FORCEPROP 1 LAST $LOCATION C66
J 0
(1525 225);
DISPLAY 1.021277 (1525 225);
DISPLAY INVISIBLE (1525 225);
FORCEPROP 2 LAST CDS_LOCATION C66
J 0
(1525 225);
DISPLAY 1.021277 (1525 225);
DISPLAY INVISIBLE (1525 225);
FORCEPROP 2 LAST $SEC 1
J 0
(1525 225);
DISPLAY 0.680851 (1525 225);
PAINT MONO (1525 225);
DISPLAY INVISIBLE (1525 225);
FORCEPROP 2 LAST CDS_SEC 1
J 0
(1525 225);
DISPLAY 1.021277 (1525 225);
DISPLAY INVISIBLE (1525 225);
FORCEADD VCC_CORE..1
(1475 350);
FORCEPROP 3 LASTPIN (1475 300) SIG_NAME P12V_S3_AUX_CPU1_NVDIMM\g
J 0
(1485 310);
DISPLAY 0.659574 (1485 310);
PAINT MONO (1485 310);
DISPLAY INVISIBLE (1485 310);
FORCEPROP 1 LAST HDL_POWER P12V_S3_AUX_CPU1_NVDIMM
J 1
(1475 400);
DISPLAY 1.148936 (1475 400);
PAINT GREEN (1475 400);
FORCEPROP 2 LAST CDS_LIB logical_power
J 0
(1475 350);
PAINT MONO (1475 350);
DISPLAY INVISIBLE (1475 350);
FORCEPROP 1 LAST PATH I127
J 0
(1525 375);
DISPLAY 0.872340 (1525 375);
PAINT AQUA (1525 375);
DISPLAY INVISIBLE (1525 375);
FORCEADD Q_CAP..1
(2100 25);
FORCEPROP 1 LAST PART_NUMBER CH6103KEA00
J 0
(2150 -125);
DISPLAY 0.978723 (2150 -125);
DISPLAY INVISIBLE (2150 -125);
FORCEPROP 1 LAST TOLERANCE 10%
J 0
(2150 -25);
DISPLAY 0.978723 (2150 -25);
FORCEPROP 1 LAST PACK_TYPE C0805
J 0
(2150 -175);
DISPLAY 0.978723 (2150 -175);
FORCEPROP 1 LAST VOLTAGE 16V
J 0
(2150 25);
DISPLAY 0.978723 (2150 25);
FORCEPROP 1 LAST VALUE 10UF
J 0
(2150 75);
DISPLAY 0.978723 (2150 75);
FORCEPROP 1 LAST MATERIAL X6S
J 0
(2150 -75);
DISPLAY 0.978723 (2150 -75);
FORCEPROP 1 LAST $LOCATION C67
J 0
(2150 125);
DISPLAY 0.978723 (2150 125);
FORCEPROP 1 LASTPIN (2100 125) $PN 1
J 0
(2110 105);
DISPLAY 0.787234 (2110 105);
FORCEPROP 1 LASTPIN (2100 -75) $PN 2
J 0
(2110 -95);
DISPLAY 0.787234 (2110 -95);
FORCEPROP 2 LAST CDS_LIB pure_quanta
J 0
(2100 25);
PAINT MONO (2100 25);
DISPLAY INVISIBLE (2100 25);
FORCEPROP 1 LAST PATH I128
J 0
(2150 175);
DISPLAY 0.978723 (2150 175);
PAINT WHITE (2150 175);
DISPLAY INVISIBLE (2150 175);
FORCEPROP 1 LAST $LOCATION C67
J 0
(2150 225);
DISPLAY 1.021277 (2150 225);
DISPLAY INVISIBLE (2150 225);
FORCEPROP 2 LAST CDS_LOCATION C67
J 0
(2150 225);
DISPLAY 1.021277 (2150 225);
DISPLAY INVISIBLE (2150 225);
FORCEPROP 2 LAST $SEC 1
J 0
(2150 225);
DISPLAY 0.680851 (2150 225);
PAINT MONO (2150 225);
DISPLAY INVISIBLE (2150 225);
FORCEPROP 2 LAST CDS_SEC 1
J 0
(2150 225);
DISPLAY 1.021277 (2150 225);
DISPLAY INVISIBLE (2150 225);
FORCEADD UNIVERSAL_GND..1
(3175 200);
FORCEPROP 3 LASTPIN (3175 250) SIG_NAME GND\g
J 0
(3185 260);
DISPLAY 0.659574 (3185 260);
PAINT MONO (3185 260);
DISPLAY INVISIBLE (3185 260);
FORCEPROP 1 LAST PATH I129
J 0
(3250 200);
DISPLAY 0.872340 (3250 200);
PAINT AQUA (3250 200);
DISPLAY INVISIBLE (3250 200);
FORCEPROP 1 LAST HDL_POWER GND
J 1
(3200 125);
DISPLAY 0.872340 (3200 125);
PAINT GREEN (3200 125);
DISPLAY INVISIBLE (3200 125);
FORCEPROP 2 LAST CDS_LIB logical_power
J 0
(3175 200);
PAINT MONO (3175 200);
DISPLAY INVISIBLE (3175 200);
FORCEADD TAP..1
R 2
(-2900 1700);
FORCEPROP 3 LASTPIN (-2850 1700) SIG_NAME M_C_CPU1_SB_CB<0>
J 0
(-2840 1710);
DISPLAY 0.659574 (-2840 1710);
PAINT MONO (-2840 1710);
DISPLAY INVISIBLE (-2840 1710);
FORCEPROP 1 LASTPIN (-2850 1700) BN 0
J 2
(-2838 1708);
DISPLAY 0.680851 (-2838 1708);
PAINT GREEN (-2838 1708);
FORCEPROP 2 LAST CDS_LIB standard
J 0
(-2900 1700);
PAINT MONO (-2900 1700);
DISPLAY INVISIBLE (-2900 1700);
FORCEPROP 1 LAST BODY_TYPE PLUMBING
J 2
(-2900 1750);
DISPLAY 0.872340 (-2900 1750);
PAINT GREEN (-2900 1750);
DISPLAY INVISIBLE (-2900 1750);
FORCEPROP 1 LAST HDL_TAP TRUE
J 2
(-3225 1575);
DISPLAY 0.872340 (-3225 1575);
DISPLAY INVISIBLE (-3225 1575);
FORCEPROP 1 LAST PATH I13
J 2
(-2898 1700);
DISPLAY 0.872340 (-2898 1700);
PAINT GREEN (-2898 1700);
DISPLAY INVISIBLE (-2898 1700);
FORCEADD TAP..1
(1500 1950);
FORCEPROP 3 LASTPIN (1450 1950) SIG_NAME M_C_CPU1_SB_DQS_DP<0>
J 0
(1460 1960);
DISPLAY 0.659574 (1460 1960);
PAINT MONO (1460 1960);
DISPLAY INVISIBLE (1460 1960);
FORCEPROP 1 LASTPIN (1450 1950) BN 0
J 0
(1438 1958);
DISPLAY 0.680851 (1438 1958);
PAINT GREEN (1438 1958);
FORCEPROP 2 LAST CDS_LIB standard
J 0
(1500 1950);
PAINT MONO (1500 1950);
DISPLAY INVISIBLE (1500 1950);
FORCEPROP 1 LAST BODY_TYPE PLUMBING
J 0
(1500 2000);
DISPLAY 0.872340 (1500 2000);
PAINT GREEN (1500 2000);
DISPLAY INVISIBLE (1500 2000);
FORCEPROP 1 LAST HDL_TAP TRUE
J 0
(1825 1825);
DISPLAY 0.872340 (1825 1825);
DISPLAY INVISIBLE (1825 1825);
FORCEPROP 1 LAST PATH I130
J 0
(1498 1950);
DISPLAY 0.872340 (1498 1950);
PAINT GREEN (1498 1950);
DISPLAY INVISIBLE (1498 1950);
FORCEADD TAP..1
(1500 2050);
FORCEPROP 3 LASTPIN (1450 2050) SIG_NAME M_C_CPU1_SB_DQS_DP<1>
J 0
(1460 2060);
DISPLAY 0.659574 (1460 2060);
PAINT MONO (1460 2060);
DISPLAY INVISIBLE (1460 2060);
FORCEPROP 1 LASTPIN (1450 2050) BN 1
J 0
(1438 2058);
DISPLAY 0.680851 (1438 2058);
PAINT GREEN (1438 2058);
FORCEPROP 2 LAST CDS_LIB standard
J 0
(1500 2050);
DISPLAY INVISIBLE (1500 2050);
FORCEPROP 1 LAST BODY_TYPE PLUMBING
J 0
(1500 2100);
DISPLAY 0.872340 (1500 2100);
PAINT GREEN (1500 2100);
DISPLAY INVISIBLE (1500 2100);
FORCEPROP 1 LAST HDL_TAP TRUE
J 0
(1825 1925);
DISPLAY 0.872340 (1825 1925);
DISPLAY INVISIBLE (1825 1925);
FORCEPROP 1 LAST PATH I131
J 0
(1498 2050);
DISPLAY 0.872340 (1498 2050);
PAINT GREEN (1498 2050);
DISPLAY INVISIBLE (1498 2050);
FORCEADD TAP..1
(1500 2150);
FORCEPROP 3 LASTPIN (1450 2150) SIG_NAME M_C_CPU1_SB_DQS_DP<2>
J 0
(1460 2160);
DISPLAY 0.659574 (1460 2160);
PAINT MONO (1460 2160);
DISPLAY INVISIBLE (1460 2160);
FORCEPROP 1 LASTPIN (1450 2150) BN 2
J 0
(1438 2158);
DISPLAY 0.680851 (1438 2158);
PAINT GREEN (1438 2158);
FORCEPROP 2 LAST CDS_LIB standard
J 0
(1500 2150);
DISPLAY INVISIBLE (1500 2150);
FORCEPROP 1 LAST BODY_TYPE PLUMBING
J 0
(1500 2200);
DISPLAY 0.872340 (1500 2200);
PAINT GREEN (1500 2200);
DISPLAY INVISIBLE (1500 2200);
FORCEPROP 1 LAST HDL_TAP TRUE
J 0
(1825 2025);
DISPLAY 0.872340 (1825 2025);
DISPLAY INVISIBLE (1825 2025);
FORCEPROP 1 LAST PATH I132
J 0
(1498 2150);
DISPLAY 0.872340 (1498 2150);
PAINT GREEN (1498 2150);
DISPLAY INVISIBLE (1498 2150);
FORCEADD TAP..1
(1500 2250);
FORCEPROP 3 LASTPIN (1450 2250) SIG_NAME M_C_CPU1_SB_DQS_DP<3>
J 0
(1460 2260);
DISPLAY 0.659574 (1460 2260);
PAINT MONO (1460 2260);
DISPLAY INVISIBLE (1460 2260);
FORCEPROP 1 LASTPIN (1450 2250) BN 3
J 0
(1438 2258);
DISPLAY 0.680851 (1438 2258);
PAINT GREEN (1438 2258);
FORCEPROP 2 LAST CDS_LIB standard
J 0
(1500 2250);
PAINT MONO (1500 2250);
DISPLAY INVISIBLE (1500 2250);
FORCEPROP 1 LAST BODY_TYPE PLUMBING
J 0
(1500 2300);
DISPLAY 0.872340 (1500 2300);
PAINT GREEN (1500 2300);
DISPLAY INVISIBLE (1500 2300);
FORCEPROP 1 LAST HDL_TAP TRUE
J 0
(1825 2125);
DISPLAY 0.872340 (1825 2125);
DISPLAY INVISIBLE (1825 2125);
FORCEPROP 1 LAST PATH I133
J 0
(1498 2250);
DISPLAY 0.872340 (1498 2250);
PAINT GREEN (1498 2250);
DISPLAY INVISIBLE (1498 2250);
FORCEADD TAP..1
(1675 2000);
FORCEPROP 3 LASTPIN (1625 2000) SIG_NAME M_C_CPU1_SB_DQS_DN<1>
J 0
(1635 2010);
DISPLAY 0.659574 (1635 2010);
PAINT MONO (1635 2010);
DISPLAY INVISIBLE (1635 2010);
FORCEPROP 1 LASTPIN (1625 2000) BN 1
J 0
(1613 2008);
DISPLAY 0.680851 (1613 2008);
PAINT GREEN (1613 2008);
FORCEPROP 2 LAST CDS_LIB standard
J 0
(1675 2000);
DISPLAY INVISIBLE (1675 2000);
FORCEPROP 1 LAST BODY_TYPE PLUMBING
J 0
(1675 2050);
DISPLAY 0.872340 (1675 2050);
PAINT GREEN (1675 2050);
DISPLAY INVISIBLE (1675 2050);
FORCEPROP 1 LAST HDL_TAP TRUE
J 0
(2000 1875);
DISPLAY 0.872340 (2000 1875);
DISPLAY INVISIBLE (2000 1875);
FORCEPROP 1 LAST PATH I134
J 0
(1673 2000);
DISPLAY 0.872340 (1673 2000);
PAINT GREEN (1673 2000);
DISPLAY INVISIBLE (1673 2000);
FORCEADD TAP..1
(1675 1900);
FORCEPROP 3 LASTPIN (1625 1900) SIG_NAME M_C_CPU1_SB_DQS_DN<0>
J 0
(1635 1910);
DISPLAY 0.659574 (1635 1910);
PAINT MONO (1635 1910);
DISPLAY INVISIBLE (1635 1910);
FORCEPROP 1 LASTPIN (1625 1900) BN 0
J 0
(1613 1908);
DISPLAY 0.680851 (1613 1908);
PAINT GREEN (1613 1908);
FORCEPROP 2 LAST CDS_LIB standard
J 0
(1675 1900);
PAINT MONO (1675 1900);
DISPLAY INVISIBLE (1675 1900);
FORCEPROP 1 LAST BODY_TYPE PLUMBING
J 0
(1675 1950);
DISPLAY 0.872340 (1675 1950);
PAINT GREEN (1675 1950);
DISPLAY INVISIBLE (1675 1950);
FORCEPROP 1 LAST HDL_TAP TRUE
J 0
(2000 1775);
DISPLAY 0.872340 (2000 1775);
DISPLAY INVISIBLE (2000 1775);
FORCEPROP 1 LAST PATH I135
J 0
(1673 1900);
DISPLAY 0.872340 (1673 1900);
PAINT GREEN (1673 1900);
DISPLAY INVISIBLE (1673 1900);
FORCEADD TAP..1
(1675 2100);
FORCEPROP 3 LASTPIN (1625 2100) SIG_NAME M_C_CPU1_SB_DQS_DN<2>
J 0
(1635 2110);
DISPLAY 0.659574 (1635 2110);
PAINT MONO (1635 2110);
DISPLAY INVISIBLE (1635 2110);
FORCEPROP 1 LASTPIN (1625 2100) BN 2
J 0
(1613 2108);
DISPLAY 0.680851 (1613 2108);
PAINT GREEN (1613 2108);
FORCEPROP 2 LAST CDS_LIB standard
J 0
(1675 2100);
DISPLAY INVISIBLE (1675 2100);
FORCEPROP 1 LAST BODY_TYPE PLUMBING
J 0
(1675 2150);
DISPLAY 0.872340 (1675 2150);
PAINT GREEN (1675 2150);
DISPLAY INVISIBLE (1675 2150);
FORCEPROP 1 LAST HDL_TAP TRUE
J 0
(2000 1975);
DISPLAY 0.872340 (2000 1975);
DISPLAY INVISIBLE (2000 1975);
FORCEPROP 1 LAST PATH I136
J 0
(1673 2100);
DISPLAY 0.872340 (1673 2100);
PAINT GREEN (1673 2100);
DISPLAY INVISIBLE (1673 2100);
FORCEADD TAP..1
(1675 2200);
FORCEPROP 3 LASTPIN (1625 2200) SIG_NAME M_C_CPU1_SB_DQS_DN<3>
J 0
(1635 2210);
DISPLAY 0.659574 (1635 2210);
PAINT MONO (1635 2210);
DISPLAY INVISIBLE (1635 2210);
FORCEPROP 1 LASTPIN (1625 2200) BN 3
J 0
(1613 2208);
DISPLAY 0.680851 (1613 2208);
PAINT GREEN (1613 2208);
FORCEPROP 2 LAST CDS_LIB standard
J 0
(1675 2200);
PAINT MONO (1675 2200);
DISPLAY INVISIBLE (1675 2200);
FORCEPROP 1 LAST BODY_TYPE PLUMBING
J 0
(1675 2250);
DISPLAY 0.872340 (1675 2250);
PAINT GREEN (1675 2250);
DISPLAY INVISIBLE (1675 2250);
FORCEPROP 1 LAST HDL_TAP TRUE
J 0
(2000 2075);
DISPLAY 0.872340 (2000 2075);
DISPLAY INVISIBLE (2000 2075);
FORCEPROP 1 LAST PATH I137
J 0
(1673 2200);
DISPLAY 0.872340 (1673 2200);
PAINT GREEN (1673 2200);
DISPLAY INVISIBLE (1673 2200);
FORCEADD TAP..1
(1500 2350);
FORCEPROP 3 LASTPIN (1450 2350) SIG_NAME M_C_CPU1_SB_DQS_DP<4>
J 0
(1460 2360);
DISPLAY 0.659574 (1460 2360);
PAINT MONO (1460 2360);
DISPLAY INVISIBLE (1460 2360);
FORCEPROP 1 LASTPIN (1450 2350) BN 4
J 0
(1438 2358);
DISPLAY 0.680851 (1438 2358);
PAINT GREEN (1438 2358);
FORCEPROP 2 LAST CDS_LIB standard
J 0
(1500 2350);
PAINT MONO (1500 2350);
DISPLAY INVISIBLE (1500 2350);
FORCEPROP 1 LAST BODY_TYPE PLUMBING
J 0
(1500 2400);
DISPLAY 0.872340 (1500 2400);
PAINT GREEN (1500 2400);
DISPLAY INVISIBLE (1500 2400);
FORCEPROP 1 LAST HDL_TAP TRUE
J 0
(1825 2225);
DISPLAY 0.872340 (1825 2225);
DISPLAY INVISIBLE (1825 2225);
FORCEPROP 1 LAST PATH I138
J 0
(1498 2350);
DISPLAY 0.872340 (1498 2350);
PAINT GREEN (1498 2350);
DISPLAY INVISIBLE (1498 2350);
FORCEADD TAP..1
(1500 2450);
FORCEPROP 3 LASTPIN (1450 2450) SIG_NAME M_C_CPU1_SB_DQS_DP<5>
J 0
(1460 2460);
DISPLAY 0.659574 (1460 2460);
PAINT MONO (1460 2460);
DISPLAY INVISIBLE (1460 2460);
FORCEPROP 1 LASTPIN (1450 2450) BN 5
J 0
(1438 2458);
DISPLAY 0.680851 (1438 2458);
PAINT GREEN (1438 2458);
FORCEPROP 2 LAST CDS_LIB standard
J 0
(1500 2450);
DISPLAY INVISIBLE (1500 2450);
FORCEPROP 1 LAST BODY_TYPE PLUMBING
J 0
(1500 2500);
DISPLAY 0.872340 (1500 2500);
PAINT GREEN (1500 2500);
DISPLAY INVISIBLE (1500 2500);
FORCEPROP 1 LAST HDL_TAP TRUE
J 0
(1825 2325);
DISPLAY 0.872340 (1825 2325);
DISPLAY INVISIBLE (1825 2325);
FORCEPROP 1 LAST PATH I139
J 0
(1498 2450);
DISPLAY 0.872340 (1498 2450);
PAINT GREEN (1498 2450);
DISPLAY INVISIBLE (1498 2450);
FORCEADD OFFPAGE..3
R 2
(-3825 2075);
FORCEPROP 2 LAST $XR1 102 
J 0
(-4194 2075);
DISPLAY 0.638298 (-4194 2075);
PAINT MONO (-4194 2075);
FORCEPROP 2 LAST $XR0 53 
J 0
(-4074 2075);
DISPLAY 0.638298 (-4074 2075);
PAINT MONO (-4074 2075);
FORCEPROP 2 LAST CDS_LIB standard
J 0
(-3825 2075);
PAINT MONO (-3825 2075);
DISPLAY INVISIBLE (-3825 2075);
FORCEPROP 1 LAST OFFPAGE TRUE
J 2
(-4150 1950);
DISPLAY 0.872340 (-4150 1950);
DISPLAY INVISIBLE (-4150 1950);
FORCEPROP 1 LAST COMMENT_BODY TRUE
J 2
(-3775 1975);
DISPLAY 0.872340 (-3775 1975);
PAINT GREEN (-3775 1975);
DISPLAY INVISIBLE (-3775 1975);
FORCEPROP 2 LAST PATH I14
J 0
(-3775 2150);
DISPLAY 1.021277 (-3775 2150);
DISPLAY INVISIBLE (-3775 2150);
FORCEADD TAP..1
(1500 2550);
FORCEPROP 3 LASTPIN (1450 2550) SIG_NAME M_C_CPU1_SB_DQS_DP<6>
J 0
(1460 2560);
DISPLAY 0.659574 (1460 2560);
PAINT MONO (1460 2560);
DISPLAY INVISIBLE (1460 2560);
FORCEPROP 1 LASTPIN (1450 2550) BN 6
J 0
(1438 2558);
DISPLAY 0.680851 (1438 2558);
PAINT GREEN (1438 2558);
FORCEPROP 2 LAST CDS_LIB standard
J 0
(1500 2550);
DISPLAY INVISIBLE (1500 2550);
FORCEPROP 1 LAST BODY_TYPE PLUMBING
J 0
(1500 2600);
DISPLAY 0.872340 (1500 2600);
PAINT GREEN (1500 2600);
DISPLAY INVISIBLE (1500 2600);
FORCEPROP 1 LAST HDL_TAP TRUE
J 0
(1825 2425);
DISPLAY 0.872340 (1825 2425);
DISPLAY INVISIBLE (1825 2425);
FORCEPROP 1 LAST PATH I140
J 0
(1498 2550);
DISPLAY 0.872340 (1498 2550);
PAINT GREEN (1498 2550);
DISPLAY INVISIBLE (1498 2550);
FORCEADD TAP..1
(1500 2650);
FORCEPROP 3 LASTPIN (1450 2650) SIG_NAME M_C_CPU1_SB_DQS_DP<7>
J 0
(1460 2660);
DISPLAY 0.659574 (1460 2660);
PAINT MONO (1460 2660);
DISPLAY INVISIBLE (1460 2660);
FORCEPROP 1 LASTPIN (1450 2650) BN 7
J 0
(1438 2658);
DISPLAY 0.680851 (1438 2658);
PAINT GREEN (1438 2658);
FORCEPROP 2 LAST CDS_LIB standard
J 0
(1500 2650);
DISPLAY INVISIBLE (1500 2650);
FORCEPROP 1 LAST BODY_TYPE PLUMBING
J 0
(1500 2700);
DISPLAY 0.872340 (1500 2700);
PAINT GREEN (1500 2700);
DISPLAY INVISIBLE (1500 2700);
FORCEPROP 1 LAST HDL_TAP TRUE
J 0
(1825 2525);
DISPLAY 0.872340 (1825 2525);
DISPLAY INVISIBLE (1825 2525);
FORCEPROP 1 LAST PATH I141
J 0
(1498 2650);
DISPLAY 0.872340 (1498 2650);
PAINT GREEN (1498 2650);
DISPLAY INVISIBLE (1498 2650);
FORCEADD TAP..1
(1500 2750);
FORCEPROP 3 LASTPIN (1450 2750) SIG_NAME M_C_CPU1_SB_DQS_DP<8>
J 0
(1460 2760);
DISPLAY 0.659574 (1460 2760);
PAINT MONO (1460 2760);
DISPLAY INVISIBLE (1460 2760);
FORCEPROP 1 LASTPIN (1450 2750) BN 8
J 0
(1438 2758);
DISPLAY 0.680851 (1438 2758);
PAINT GREEN (1438 2758);
FORCEPROP 2 LAST CDS_LIB standard
J 0
(1500 2750);
DISPLAY INVISIBLE (1500 2750);
FORCEPROP 1 LAST BODY_TYPE PLUMBING
J 0
(1500 2800);
DISPLAY 0.872340 (1500 2800);
PAINT GREEN (1500 2800);
DISPLAY INVISIBLE (1500 2800);
FORCEPROP 1 LAST HDL_TAP TRUE
J 0
(1825 2625);
DISPLAY 0.872340 (1825 2625);
DISPLAY INVISIBLE (1825 2625);
FORCEPROP 1 LAST PATH I142
J 0
(1498 2750);
DISPLAY 0.872340 (1498 2750);
PAINT GREEN (1498 2750);
DISPLAY INVISIBLE (1498 2750);
FORCEADD TAP..1
(1675 2300);
FORCEPROP 3 LASTPIN (1625 2300) SIG_NAME M_C_CPU1_SB_DQS_DN<4>
J 0
(1635 2310);
DISPLAY 0.659574 (1635 2310);
PAINT MONO (1635 2310);
DISPLAY INVISIBLE (1635 2310);
FORCEPROP 1 LASTPIN (1625 2300) BN 4
J 0
(1613 2308);
DISPLAY 0.680851 (1613 2308);
PAINT GREEN (1613 2308);
FORCEPROP 2 LAST CDS_LIB standard
J 0
(1675 2300);
PAINT MONO (1675 2300);
DISPLAY INVISIBLE (1675 2300);
FORCEPROP 1 LAST BODY_TYPE PLUMBING
J 0
(1675 2350);
DISPLAY 0.872340 (1675 2350);
PAINT GREEN (1675 2350);
DISPLAY INVISIBLE (1675 2350);
FORCEPROP 1 LAST HDL_TAP TRUE
J 0
(2000 2175);
DISPLAY 0.872340 (2000 2175);
DISPLAY INVISIBLE (2000 2175);
FORCEPROP 1 LAST PATH I143
J 0
(1673 2300);
DISPLAY 0.872340 (1673 2300);
PAINT GREEN (1673 2300);
DISPLAY INVISIBLE (1673 2300);
FORCEADD TAP..1
(1675 2500);
FORCEPROP 3 LASTPIN (1625 2500) SIG_NAME M_C_CPU1_SB_DQS_DN<6>
J 0
(1635 2510);
DISPLAY 0.659574 (1635 2510);
PAINT MONO (1635 2510);
DISPLAY INVISIBLE (1635 2510);
FORCEPROP 1 LASTPIN (1625 2500) BN 6
J 0
(1613 2508);
DISPLAY 0.680851 (1613 2508);
PAINT GREEN (1613 2508);
FORCEPROP 2 LAST CDS_LIB standard
J 0
(1675 2500);
DISPLAY INVISIBLE (1675 2500);
FORCEPROP 1 LAST BODY_TYPE PLUMBING
J 0
(1675 2550);
DISPLAY 0.872340 (1675 2550);
PAINT GREEN (1675 2550);
DISPLAY INVISIBLE (1675 2550);
FORCEPROP 1 LAST HDL_TAP TRUE
J 0
(2000 2375);
DISPLAY 0.872340 (2000 2375);
DISPLAY INVISIBLE (2000 2375);
FORCEPROP 1 LAST PATH I144
J 0
(1673 2500);
DISPLAY 0.872340 (1673 2500);
PAINT GREEN (1673 2500);
DISPLAY INVISIBLE (1673 2500);
FORCEADD TAP..1
(1675 2400);
FORCEPROP 3 LASTPIN (1625 2400) SIG_NAME M_C_CPU1_SB_DQS_DN<5>
J 0
(1635 2410);
DISPLAY 0.659574 (1635 2410);
PAINT MONO (1635 2410);
DISPLAY INVISIBLE (1635 2410);
FORCEPROP 1 LASTPIN (1625 2400) BN 5
J 0
(1613 2408);
DISPLAY 0.680851 (1613 2408);
PAINT GREEN (1613 2408);
FORCEPROP 2 LAST CDS_LIB standard
J 0
(1675 2400);
DISPLAY INVISIBLE (1675 2400);
FORCEPROP 1 LAST BODY_TYPE PLUMBING
J 0
(1675 2450);
DISPLAY 0.872340 (1675 2450);
PAINT GREEN (1675 2450);
DISPLAY INVISIBLE (1675 2450);
FORCEPROP 1 LAST HDL_TAP TRUE
J 0
(2000 2275);
DISPLAY 0.872340 (2000 2275);
DISPLAY INVISIBLE (2000 2275);
FORCEPROP 1 LAST PATH I145
J 0
(1673 2400);
DISPLAY 0.872340 (1673 2400);
PAINT GREEN (1673 2400);
DISPLAY INVISIBLE (1673 2400);
FORCEADD TAP..1
(1675 2600);
FORCEPROP 3 LASTPIN (1625 2600) SIG_NAME M_C_CPU1_SB_DQS_DN<7>
J 0
(1635 2610);
DISPLAY 0.659574 (1635 2610);
PAINT MONO (1635 2610);
DISPLAY INVISIBLE (1635 2610);
FORCEPROP 1 LASTPIN (1625 2600) BN 7
J 0
(1613 2608);
DISPLAY 0.680851 (1613 2608);
PAINT GREEN (1613 2608);
FORCEPROP 2 LAST CDS_LIB standard
J 0
(1675 2600);
DISPLAY INVISIBLE (1675 2600);
FORCEPROP 1 LAST BODY_TYPE PLUMBING
J 0
(1675 2650);
DISPLAY 0.872340 (1675 2650);
PAINT GREEN (1675 2650);
DISPLAY INVISIBLE (1675 2650);
FORCEPROP 1 LAST HDL_TAP TRUE
J 0
(2000 2475);
DISPLAY 0.872340 (2000 2475);
DISPLAY INVISIBLE (2000 2475);
FORCEPROP 1 LAST PATH I146
J 0
(1673 2600);
DISPLAY 0.872340 (1673 2600);
PAINT GREEN (1673 2600);
DISPLAY INVISIBLE (1673 2600);
FORCEADD TAP..1
(1675 2700);
FORCEPROP 3 LASTPIN (1625 2700) SIG_NAME M_C_CPU1_SB_DQS_DN<8>
J 0
(1635 2710);
DISPLAY 0.659574 (1635 2710);
PAINT MONO (1635 2710);
DISPLAY INVISIBLE (1635 2710);
FORCEPROP 1 LASTPIN (1625 2700) BN 8
J 0
(1613 2708);
DISPLAY 0.680851 (1613 2708);
PAINT GREEN (1613 2708);
FORCEPROP 2 LAST CDS_LIB standard
J 0
(1675 2700);
DISPLAY INVISIBLE (1675 2700);
FORCEPROP 1 LAST BODY_TYPE PLUMBING
J 0
(1675 2750);
DISPLAY 0.872340 (1675 2750);
PAINT GREEN (1675 2750);
DISPLAY INVISIBLE (1675 2750);
FORCEPROP 1 LAST HDL_TAP TRUE
J 0
(2000 2575);
DISPLAY 0.872340 (2000 2575);
DISPLAY INVISIBLE (2000 2575);
FORCEPROP 1 LAST PATH I147
J 0
(1673 2700);
DISPLAY 0.872340 (1673 2700);
PAINT GREEN (1673 2700);
DISPLAY INVISIBLE (1673 2700);
FORCEADD TAP..1
(1500 2850);
FORCEPROP 3 LASTPIN (1450 2850) SIG_NAME M_C_CPU1_SB_DQS_DP<9>
J 0
(1460 2860);
DISPLAY 0.659574 (1460 2860);
PAINT MONO (1460 2860);
DISPLAY INVISIBLE (1460 2860);
FORCEPROP 1 LASTPIN (1450 2850) BN 9
J 0
(1438 2858);
DISPLAY 0.680851 (1438 2858);
PAINT GREEN (1438 2858);
FORCEPROP 2 LAST CDS_LIB standard
J 0
(1500 2850);
DISPLAY INVISIBLE (1500 2850);
FORCEPROP 1 LAST BODY_TYPE PLUMBING
J 0
(1500 2900);
DISPLAY 0.872340 (1500 2900);
PAINT GREEN (1500 2900);
DISPLAY INVISIBLE (1500 2900);
FORCEPROP 1 LAST HDL_TAP TRUE
J 0
(1825 2725);
DISPLAY 0.872340 (1825 2725);
DISPLAY INVISIBLE (1825 2725);
FORCEPROP 1 LAST PATH I148
J 0
(1498 2850);
DISPLAY 0.872340 (1498 2850);
PAINT GREEN (1498 2850);
DISPLAY INVISIBLE (1498 2850);
FORCEADD TAP..1
(1500 3000);
FORCEPROP 3 LASTPIN (1450 3000) SIG_NAME M_C_CPU1_SA_DQS_DP<0>
J 0
(1460 3010);
DISPLAY 0.659574 (1460 3010);
PAINT MONO (1460 3010);
DISPLAY INVISIBLE (1460 3010);
FORCEPROP 1 LASTPIN (1450 3000) BN 0
J 0
(1438 3008);
DISPLAY 0.680851 (1438 3008);
PAINT GREEN (1438 3008);
FORCEPROP 2 LAST CDS_LIB standard
J 0
(1500 3000);
PAINT MONO (1500 3000);
DISPLAY INVISIBLE (1500 3000);
FORCEPROP 1 LAST BODY_TYPE PLUMBING
J 0
(1500 3050);
DISPLAY 0.872340 (1500 3050);
PAINT GREEN (1500 3050);
DISPLAY INVISIBLE (1500 3050);
FORCEPROP 1 LAST HDL_TAP TRUE
J 0
(1825 2875);
DISPLAY 0.872340 (1825 2875);
DISPLAY INVISIBLE (1825 2875);
FORCEPROP 1 LAST PATH I149
J 0
(1498 3000);
DISPLAY 0.872340 (1498 3000);
PAINT GREEN (1498 3000);
DISPLAY INVISIBLE (1498 3000);
FORCEADD OFFPAGE..3
R 2
(-3825 2525);
FORCEPROP 2 LAST $XR1 102 
J 0
(-4194 2525);
DISPLAY 0.638298 (-4194 2525);
PAINT MONO (-4194 2525);
FORCEPROP 2 LAST $XR0 53 
J 0
(-4074 2525);
DISPLAY 0.638298 (-4074 2525);
PAINT MONO (-4074 2525);
FORCEPROP 2 LAST CDS_LIB standard
J 0
(-3825 2525);
PAINT MONO (-3825 2525);
DISPLAY INVISIBLE (-3825 2525);
FORCEPROP 1 LAST OFFPAGE TRUE
J 2
(-4150 2400);
DISPLAY 0.872340 (-4150 2400);
DISPLAY INVISIBLE (-4150 2400);
FORCEPROP 1 LAST COMMENT_BODY TRUE
J 2
(-3775 2425);
DISPLAY 0.872340 (-3775 2425);
PAINT GREEN (-3775 2425);
DISPLAY INVISIBLE (-3775 2425);
FORCEPROP 2 LAST PATH I15
J 0
(-3775 2600);
DISPLAY 1.021277 (-3775 2600);
DISPLAY INVISIBLE (-3775 2600);
FORCEADD TAP..1
(1500 3100);
FORCEPROP 3 LASTPIN (1450 3100) SIG_NAME M_C_CPU1_SA_DQS_DP<1>
J 0
(1460 3110);
DISPLAY 0.659574 (1460 3110);
PAINT MONO (1460 3110);
DISPLAY INVISIBLE (1460 3110);
FORCEPROP 1 LASTPIN (1450 3100) BN 1
J 0
(1438 3108);
DISPLAY 0.680851 (1438 3108);
PAINT GREEN (1438 3108);
FORCEPROP 2 LAST CDS_LIB standard
J 0
(1500 3100);
DISPLAY INVISIBLE (1500 3100);
FORCEPROP 1 LAST BODY_TYPE PLUMBING
J 0
(1500 3150);
DISPLAY 0.872340 (1500 3150);
PAINT GREEN (1500 3150);
DISPLAY INVISIBLE (1500 3150);
FORCEPROP 1 LAST HDL_TAP TRUE
J 0
(1825 2975);
DISPLAY 0.872340 (1825 2975);
DISPLAY INVISIBLE (1825 2975);
FORCEPROP 1 LAST PATH I150
J 0
(1498 3100);
DISPLAY 0.872340 (1498 3100);
PAINT GREEN (1498 3100);
DISPLAY INVISIBLE (1498 3100);
FORCEADD TAP..1
(1500 3200);
FORCEPROP 3 LASTPIN (1450 3200) SIG_NAME M_C_CPU1_SA_DQS_DP<2>
J 0
(1460 3210);
DISPLAY 0.659574 (1460 3210);
PAINT MONO (1460 3210);
DISPLAY INVISIBLE (1460 3210);
FORCEPROP 1 LASTPIN (1450 3200) BN 2
J 0
(1438 3208);
DISPLAY 0.680851 (1438 3208);
PAINT GREEN (1438 3208);
FORCEPROP 2 LAST CDS_LIB standard
J 0
(1500 3200);
DISPLAY INVISIBLE (1500 3200);
FORCEPROP 1 LAST BODY_TYPE PLUMBING
J 0
(1500 3250);
DISPLAY 0.872340 (1500 3250);
PAINT GREEN (1500 3250);
DISPLAY INVISIBLE (1500 3250);
FORCEPROP 1 LAST HDL_TAP TRUE
J 0
(1825 3075);
DISPLAY 0.872340 (1825 3075);
DISPLAY INVISIBLE (1825 3075);
FORCEPROP 1 LAST PATH I151
J 0
(1498 3200);
DISPLAY 0.872340 (1498 3200);
PAINT GREEN (1498 3200);
DISPLAY INVISIBLE (1498 3200);
FORCEADD TAP..1
(1675 2800);
FORCEPROP 3 LASTPIN (1625 2800) SIG_NAME M_C_CPU1_SB_DQS_DN<9>
J 0
(1635 2810);
DISPLAY 0.659574 (1635 2810);
PAINT MONO (1635 2810);
DISPLAY INVISIBLE (1635 2810);
FORCEPROP 1 LASTPIN (1625 2800) BN 9
J 0
(1613 2808);
DISPLAY 0.680851 (1613 2808);
PAINT GREEN (1613 2808);
FORCEPROP 2 LAST CDS_LIB standard
J 0
(1675 2800);
DISPLAY INVISIBLE (1675 2800);
FORCEPROP 1 LAST BODY_TYPE PLUMBING
J 0
(1675 2850);
DISPLAY 0.872340 (1675 2850);
PAINT GREEN (1675 2850);
DISPLAY INVISIBLE (1675 2850);
FORCEPROP 1 LAST HDL_TAP TRUE
J 0
(2000 2675);
DISPLAY 0.872340 (2000 2675);
DISPLAY INVISIBLE (2000 2675);
FORCEPROP 1 LAST PATH I152
J 0
(1673 2800);
DISPLAY 0.872340 (1673 2800);
PAINT GREEN (1673 2800);
DISPLAY INVISIBLE (1673 2800);
FORCEADD TAP..1
(1675 2950);
FORCEPROP 3 LASTPIN (1625 2950) SIG_NAME M_C_CPU1_SA_DQS_DN<0>
J 0
(1635 2960);
DISPLAY 0.659574 (1635 2960);
PAINT MONO (1635 2960);
DISPLAY INVISIBLE (1635 2960);
FORCEPROP 1 LASTPIN (1625 2950) BN 0
J 0
(1613 2958);
DISPLAY 0.680851 (1613 2958);
PAINT GREEN (1613 2958);
FORCEPROP 2 LAST CDS_LIB standard
J 0
(1675 2950);
PAINT MONO (1675 2950);
DISPLAY INVISIBLE (1675 2950);
FORCEPROP 1 LAST BODY_TYPE PLUMBING
J 0
(1675 3000);
DISPLAY 0.872340 (1675 3000);
PAINT GREEN (1675 3000);
DISPLAY INVISIBLE (1675 3000);
FORCEPROP 1 LAST HDL_TAP TRUE
J 0
(2000 2825);
DISPLAY 0.872340 (2000 2825);
DISPLAY INVISIBLE (2000 2825);
FORCEPROP 1 LAST PATH I153
J 0
(1673 2950);
DISPLAY 0.872340 (1673 2950);
PAINT GREEN (1673 2950);
DISPLAY INVISIBLE (1673 2950);
FORCEADD TAP..1
(1675 3150);
FORCEPROP 3 LASTPIN (1625 3150) SIG_NAME M_C_CPU1_SA_DQS_DN<2>
J 0
(1635 3160);
DISPLAY 0.659574 (1635 3160);
PAINT MONO (1635 3160);
DISPLAY INVISIBLE (1635 3160);
FORCEPROP 1 LASTPIN (1625 3150) BN 2
J 0
(1613 3158);
DISPLAY 0.680851 (1613 3158);
PAINT GREEN (1613 3158);
FORCEPROP 2 LAST CDS_LIB standard
J 0
(1675 3150);
DISPLAY INVISIBLE (1675 3150);
FORCEPROP 1 LAST BODY_TYPE PLUMBING
J 0
(1675 3200);
DISPLAY 0.872340 (1675 3200);
PAINT GREEN (1675 3200);
DISPLAY INVISIBLE (1675 3200);
FORCEPROP 1 LAST HDL_TAP TRUE
J 0
(2000 3025);
DISPLAY 0.872340 (2000 3025);
DISPLAY INVISIBLE (2000 3025);
FORCEPROP 1 LAST PATH I154
J 0
(1673 3150);
DISPLAY 0.872340 (1673 3150);
PAINT GREEN (1673 3150);
DISPLAY INVISIBLE (1673 3150);
FORCEADD TAP..1
(1675 3050);
FORCEPROP 3 LASTPIN (1625 3050) SIG_NAME M_C_CPU1_SA_DQS_DN<1>
J 0
(1635 3060);
DISPLAY 0.659574 (1635 3060);
PAINT MONO (1635 3060);
DISPLAY INVISIBLE (1635 3060);
FORCEPROP 1 LASTPIN (1625 3050) BN 1
J 0
(1613 3058);
DISPLAY 0.680851 (1613 3058);
PAINT GREEN (1613 3058);
FORCEPROP 2 LAST CDS_LIB standard
J 0
(1675 3050);
DISPLAY INVISIBLE (1675 3050);
FORCEPROP 1 LAST BODY_TYPE PLUMBING
J 0
(1675 3100);
DISPLAY 0.872340 (1675 3100);
PAINT GREEN (1675 3100);
DISPLAY INVISIBLE (1675 3100);
FORCEPROP 1 LAST HDL_TAP TRUE
J 0
(2000 2925);
DISPLAY 0.872340 (2000 2925);
DISPLAY INVISIBLE (2000 2925);
FORCEPROP 1 LAST PATH I155
J 0
(1673 3050);
DISPLAY 0.872340 (1673 3050);
PAINT GREEN (1673 3050);
DISPLAY INVISIBLE (1673 3050);
FORCEADD TAP..1
(1675 3250);
FORCEPROP 3 LASTPIN (1625 3250) SIG_NAME M_C_CPU1_SA_DQS_DN<3>
J 0
(1635 3260);
DISPLAY 0.659574 (1635 3260);
PAINT MONO (1635 3260);
DISPLAY INVISIBLE (1635 3260);
FORCEPROP 1 LASTPIN (1625 3250) BN 3
J 0
(1613 3258);
DISPLAY 0.680851 (1613 3258);
PAINT GREEN (1613 3258);
FORCEPROP 2 LAST CDS_LIB standard
J 0
(1675 3250);
PAINT MONO (1675 3250);
DISPLAY INVISIBLE (1675 3250);
FORCEPROP 1 LAST BODY_TYPE PLUMBING
J 0
(1675 3300);
DISPLAY 0.872340 (1675 3300);
PAINT GREEN (1675 3300);
DISPLAY INVISIBLE (1675 3300);
FORCEPROP 1 LAST HDL_TAP TRUE
J 0
(2000 3125);
DISPLAY 0.872340 (2000 3125);
DISPLAY INVISIBLE (2000 3125);
FORCEPROP 1 LAST PATH I156
J 0
(1673 3250);
DISPLAY 0.872340 (1673 3250);
PAINT GREEN (1673 3250);
DISPLAY INVISIBLE (1673 3250);
FORCEADD TAP..1
(1500 3300);
FORCEPROP 3 LASTPIN (1450 3300) SIG_NAME M_C_CPU1_SA_DQS_DP<3>
J 0
(1460 3310);
DISPLAY 0.659574 (1460 3310);
PAINT MONO (1460 3310);
DISPLAY INVISIBLE (1460 3310);
FORCEPROP 1 LASTPIN (1450 3300) BN 3
J 0
(1438 3308);
DISPLAY 0.680851 (1438 3308);
PAINT GREEN (1438 3308);
FORCEPROP 2 LAST CDS_LIB standard
J 0
(1500 3300);
PAINT MONO (1500 3300);
DISPLAY INVISIBLE (1500 3300);
FORCEPROP 1 LAST BODY_TYPE PLUMBING
J 0
(1500 3350);
DISPLAY 0.872340 (1500 3350);
PAINT GREEN (1500 3350);
DISPLAY INVISIBLE (1500 3350);
FORCEPROP 1 LAST HDL_TAP TRUE
J 0
(1825 3175);
DISPLAY 0.872340 (1825 3175);
DISPLAY INVISIBLE (1825 3175);
FORCEPROP 1 LAST PATH I157
J 0
(1498 3300);
DISPLAY 0.872340 (1498 3300);
PAINT GREEN (1498 3300);
DISPLAY INVISIBLE (1498 3300);
FORCEADD TAP..1
(1500 3400);
FORCEPROP 3 LASTPIN (1450 3400) SIG_NAME M_C_CPU1_SA_DQS_DP<4>
J 0
(1460 3410);
DISPLAY 0.659574 (1460 3410);
PAINT MONO (1460 3410);
DISPLAY INVISIBLE (1460 3410);
FORCEPROP 1 LASTPIN (1450 3400) BN 4
J 0
(1438 3408);
DISPLAY 0.680851 (1438 3408);
PAINT GREEN (1438 3408);
FORCEPROP 2 LAST CDS_LIB standard
J 0
(1500 3400);
PAINT MONO (1500 3400);
DISPLAY INVISIBLE (1500 3400);
FORCEPROP 1 LAST BODY_TYPE PLUMBING
J 0
(1500 3450);
DISPLAY 0.872340 (1500 3450);
PAINT GREEN (1500 3450);
DISPLAY INVISIBLE (1500 3450);
FORCEPROP 1 LAST HDL_TAP TRUE
J 0
(1825 3275);
DISPLAY 0.872340 (1825 3275);
DISPLAY INVISIBLE (1825 3275);
FORCEPROP 1 LAST PATH I158
J 0
(1498 3400);
DISPLAY 0.872340 (1498 3400);
PAINT GREEN (1498 3400);
DISPLAY INVISIBLE (1498 3400);
FORCEADD TAP..1
(1500 3500);
FORCEPROP 3 LASTPIN (1450 3500) SIG_NAME M_C_CPU1_SA_DQS_DP<5>
J 0
(1460 3510);
DISPLAY 0.659574 (1460 3510);
PAINT MONO (1460 3510);
DISPLAY INVISIBLE (1460 3510);
FORCEPROP 1 LASTPIN (1450 3500) BN 5
J 0
(1438 3508);
DISPLAY 0.680851 (1438 3508);
PAINT GREEN (1438 3508);
FORCEPROP 2 LAST CDS_LIB standard
J 0
(1500 3500);
DISPLAY INVISIBLE (1500 3500);
FORCEPROP 1 LAST BODY_TYPE PLUMBING
J 0
(1500 3550);
DISPLAY 0.872340 (1500 3550);
PAINT GREEN (1500 3550);
DISPLAY INVISIBLE (1500 3550);
FORCEPROP 1 LAST HDL_TAP TRUE
J 0
(1825 3375);
DISPLAY 0.872340 (1825 3375);
DISPLAY INVISIBLE (1825 3375);
FORCEPROP 1 LAST PATH I159
J 0
(1498 3500);
DISPLAY 0.872340 (1498 3500);
PAINT GREEN (1498 3500);
DISPLAY INVISIBLE (1498 3500);
FORCEADD OFFPAGE..1
(-3825 2600);
FORCEPROP 2 LAST $XR0 53 
J 0
(-4046 2600);
DISPLAY 0.638298 (-4046 2600);
PAINT MONO (-4046 2600);
FORCEPROP 2 LAST CDS_LIB standard
J 0
(-3825 2600);
PAINT MONO (-3825 2600);
DISPLAY INVISIBLE (-3825 2600);
FORCEPROP 1 LAST OFFPAGE TRUE
J 0
(-3500 2475);
DISPLAY 0.872340 (-3500 2475);
DISPLAY INVISIBLE (-3500 2475);
FORCEPROP 1 LAST COMMENT_BODY TRUE
J 0
(-3700 2500);
DISPLAY 0.872340 (-3700 2500);
PAINT GREEN (-3700 2500);
DISPLAY INVISIBLE (-3700 2500);
FORCEPROP 2 LAST PATH I16
J 0
(-3775 2675);
DISPLAY 1.021277 (-3775 2675);
DISPLAY INVISIBLE (-3775 2675);
FORCEADD TAP..1
(1500 3600);
FORCEPROP 3 LASTPIN (1450 3600) SIG_NAME M_C_CPU1_SA_DQS_DP<6>
J 0
(1460 3610);
DISPLAY 0.659574 (1460 3610);
PAINT MONO (1460 3610);
DISPLAY INVISIBLE (1460 3610);
FORCEPROP 1 LASTPIN (1450 3600) BN 6
J 0
(1438 3608);
DISPLAY 0.680851 (1438 3608);
PAINT GREEN (1438 3608);
FORCEPROP 2 LAST CDS_LIB standard
J 0
(1500 3600);
DISPLAY INVISIBLE (1500 3600);
FORCEPROP 1 LAST BODY_TYPE PLUMBING
J 0
(1500 3650);
DISPLAY 0.872340 (1500 3650);
PAINT GREEN (1500 3650);
DISPLAY INVISIBLE (1500 3650);
FORCEPROP 1 LAST HDL_TAP TRUE
J 0
(1825 3475);
DISPLAY 0.872340 (1825 3475);
DISPLAY INVISIBLE (1825 3475);
FORCEPROP 1 LAST PATH I160
J 0
(1498 3600);
DISPLAY 0.872340 (1498 3600);
PAINT GREEN (1498 3600);
DISPLAY INVISIBLE (1498 3600);
FORCEADD TAP..1
(1500 3700);
FORCEPROP 3 LASTPIN (1450 3700) SIG_NAME M_C_CPU1_SA_DQS_DP<7>
J 0
(1460 3710);
DISPLAY 0.659574 (1460 3710);
PAINT MONO (1460 3710);
DISPLAY INVISIBLE (1460 3710);
FORCEPROP 1 LASTPIN (1450 3700) BN 7
J 0
(1438 3708);
DISPLAY 0.680851 (1438 3708);
PAINT GREEN (1438 3708);
FORCEPROP 2 LAST CDS_LIB standard
J 0
(1500 3700);
DISPLAY INVISIBLE (1500 3700);
FORCEPROP 1 LAST BODY_TYPE PLUMBING
J 0
(1500 3750);
DISPLAY 0.872340 (1500 3750);
PAINT GREEN (1500 3750);
DISPLAY INVISIBLE (1500 3750);
FORCEPROP 1 LAST HDL_TAP TRUE
J 0
(1825 3575);
DISPLAY 0.872340 (1825 3575);
DISPLAY INVISIBLE (1825 3575);
FORCEPROP 1 LAST PATH I161
J 0
(1498 3700);
DISPLAY 0.872340 (1498 3700);
PAINT GREEN (1498 3700);
DISPLAY INVISIBLE (1498 3700);
FORCEADD TAP..1
(1675 3350);
FORCEPROP 3 LASTPIN (1625 3350) SIG_NAME M_C_CPU1_SA_DQS_DN<4>
J 0
(1635 3360);
DISPLAY 0.659574 (1635 3360);
PAINT MONO (1635 3360);
DISPLAY INVISIBLE (1635 3360);
FORCEPROP 1 LASTPIN (1625 3350) BN 4
J 0
(1613 3358);
DISPLAY 0.680851 (1613 3358);
PAINT GREEN (1613 3358);
FORCEPROP 2 LAST CDS_LIB standard
J 0
(1675 3350);
PAINT MONO (1675 3350);
DISPLAY INVISIBLE (1675 3350);
FORCEPROP 1 LAST BODY_TYPE PLUMBING
J 0
(1675 3400);
DISPLAY 0.872340 (1675 3400);
PAINT GREEN (1675 3400);
DISPLAY INVISIBLE (1675 3400);
FORCEPROP 1 LAST HDL_TAP TRUE
J 0
(2000 3225);
DISPLAY 0.872340 (2000 3225);
DISPLAY INVISIBLE (2000 3225);
FORCEPROP 1 LAST PATH I162
J 0
(1673 3350);
DISPLAY 0.872340 (1673 3350);
PAINT GREEN (1673 3350);
DISPLAY INVISIBLE (1673 3350);
FORCEADD TAP..1
(1675 3450);
FORCEPROP 3 LASTPIN (1625 3450) SIG_NAME M_C_CPU1_SA_DQS_DN<5>
J 0
(1635 3460);
DISPLAY 0.659574 (1635 3460);
PAINT MONO (1635 3460);
DISPLAY INVISIBLE (1635 3460);
FORCEPROP 1 LASTPIN (1625 3450) BN 5
J 0
(1613 3458);
DISPLAY 0.680851 (1613 3458);
PAINT GREEN (1613 3458);
FORCEPROP 2 LAST CDS_LIB standard
J 0
(1675 3450);
DISPLAY INVISIBLE (1675 3450);
FORCEPROP 1 LAST BODY_TYPE PLUMBING
J 0
(1675 3500);
DISPLAY 0.872340 (1675 3500);
PAINT GREEN (1675 3500);
DISPLAY INVISIBLE (1675 3500);
FORCEPROP 1 LAST HDL_TAP TRUE
J 0
(2000 3325);
DISPLAY 0.872340 (2000 3325);
DISPLAY INVISIBLE (2000 3325);
FORCEPROP 1 LAST PATH I163
J 0
(1673 3450);
DISPLAY 0.872340 (1673 3450);
PAINT GREEN (1673 3450);
DISPLAY INVISIBLE (1673 3450);
FORCEADD TAP..1
(1675 3650);
FORCEPROP 3 LASTPIN (1625 3650) SIG_NAME M_C_CPU1_SA_DQS_DN<7>
J 0
(1635 3660);
DISPLAY 0.659574 (1635 3660);
PAINT MONO (1635 3660);
DISPLAY INVISIBLE (1635 3660);
FORCEPROP 1 LASTPIN (1625 3650) BN 7
J 0
(1613 3658);
DISPLAY 0.680851 (1613 3658);
PAINT GREEN (1613 3658);
FORCEPROP 2 LAST CDS_LIB standard
J 0
(1675 3650);
DISPLAY INVISIBLE (1675 3650);
FORCEPROP 1 LAST BODY_TYPE PLUMBING
J 0
(1675 3700);
DISPLAY 0.872340 (1675 3700);
PAINT GREEN (1675 3700);
DISPLAY INVISIBLE (1675 3700);
FORCEPROP 1 LAST HDL_TAP TRUE
J 0
(2000 3525);
DISPLAY 0.872340 (2000 3525);
DISPLAY INVISIBLE (2000 3525);
FORCEPROP 1 LAST PATH I164
J 0
(1673 3650);
DISPLAY 0.872340 (1673 3650);
PAINT GREEN (1673 3650);
DISPLAY INVISIBLE (1673 3650);
FORCEADD TAP..1
(1675 3550);
FORCEPROP 3 LASTPIN (1625 3550) SIG_NAME M_C_CPU1_SA_DQS_DN<6>
J 0
(1635 3560);
DISPLAY 0.659574 (1635 3560);
PAINT MONO (1635 3560);
DISPLAY INVISIBLE (1635 3560);
FORCEPROP 1 LASTPIN (1625 3550) BN 6
J 0
(1613 3558);
DISPLAY 0.680851 (1613 3558);
PAINT GREEN (1613 3558);
FORCEPROP 2 LAST CDS_LIB standard
J 0
(1675 3550);
DISPLAY INVISIBLE (1675 3550);
FORCEPROP 1 LAST BODY_TYPE PLUMBING
J 0
(1675 3600);
DISPLAY 0.872340 (1675 3600);
PAINT GREEN (1675 3600);
DISPLAY INVISIBLE (1675 3600);
FORCEPROP 1 LAST HDL_TAP TRUE
J 0
(2000 3425);
DISPLAY 0.872340 (2000 3425);
DISPLAY INVISIBLE (2000 3425);
FORCEPROP 1 LAST PATH I165
J 0
(1673 3550);
DISPLAY 0.872340 (1673 3550);
PAINT GREEN (1673 3550);
DISPLAY INVISIBLE (1673 3550);
FORCEADD TAP..1
(1675 3750);
FORCEPROP 3 LASTPIN (1625 3750) SIG_NAME M_C_CPU1_SA_DQS_DN<8>
J 0
(1635 3760);
DISPLAY 0.659574 (1635 3760);
PAINT MONO (1635 3760);
DISPLAY INVISIBLE (1635 3760);
FORCEPROP 1 LASTPIN (1625 3750) BN 8
J 0
(1613 3758);
DISPLAY 0.680851 (1613 3758);
PAINT GREEN (1613 3758);
FORCEPROP 2 LAST CDS_LIB standard
J 0
(1675 3750);
DISPLAY INVISIBLE (1675 3750);
FORCEPROP 1 LAST BODY_TYPE PLUMBING
J 0
(1675 3800);
DISPLAY 0.872340 (1675 3800);
PAINT GREEN (1675 3800);
DISPLAY INVISIBLE (1675 3800);
FORCEPROP 1 LAST HDL_TAP TRUE
J 0
(2000 3625);
DISPLAY 0.872340 (2000 3625);
DISPLAY INVISIBLE (2000 3625);
FORCEPROP 1 LAST PATH I166
J 0
(1673 3750);
DISPLAY 0.872340 (1673 3750);
PAINT GREEN (1673 3750);
DISPLAY INVISIBLE (1673 3750);
FORCEADD OFFPAGE..2
(2625 2875);
FORCEPROP 2 LAST $XR1 102 
J 0
(2904 2875);
DISPLAY 0.638298 (2904 2875);
PAINT MONO (2904 2875);
FORCEPROP 2 LAST $XR0 53 
J 0
(2814 2875);
DISPLAY 0.638298 (2814 2875);
PAINT MONO (2814 2875);
FORCEPROP 2 LAST CDS_LIB standard
J 0
(2625 2875);
PAINT MONO (2625 2875);
DISPLAY INVISIBLE (2625 2875);
FORCEPROP 1 LAST OFFPAGE TRUE
J 0
(2950 2750);
DISPLAY 1.170213 (2950 2750);
PAINT GREEN (2950 2750);
DISPLAY INVISIBLE (2950 2750);
FORCEPROP 1 LAST COMMENT_BODY TRUE
J 0
(2580 2780);
DISPLAY 1.170213 (2580 2780);
PAINT GREEN (2580 2780);
DISPLAY INVISIBLE (2580 2780);
FORCEPROP 2 LAST PATH I167
J 0
(2800 2950);
DISPLAY 1.021277 (2800 2950);
DISPLAY INVISIBLE (2800 2950);
FORCEADD OFFPAGE..2
(2625 2825);
FORCEPROP 2 LAST $XR1 102 
J 0
(2904 2825);
DISPLAY 0.638298 (2904 2825);
PAINT MONO (2904 2825);
FORCEPROP 2 LAST $XR0 53 
J 0
(2814 2825);
DISPLAY 0.638298 (2814 2825);
PAINT MONO (2814 2825);
FORCEPROP 2 LAST CDS_LIB standard
J 0
(2625 2825);
PAINT MONO (2625 2825);
DISPLAY INVISIBLE (2625 2825);
FORCEPROP 1 LAST OFFPAGE TRUE
J 0
(2950 2700);
DISPLAY 1.170213 (2950 2700);
PAINT GREEN (2950 2700);
DISPLAY INVISIBLE (2950 2700);
FORCEPROP 1 LAST COMMENT_BODY TRUE
J 0
(2580 2730);
DISPLAY 1.170213 (2580 2730);
PAINT GREEN (2580 2730);
DISPLAY INVISIBLE (2580 2730);
FORCEPROP 2 LAST PATH I168
J 0
(2800 2900);
DISPLAY 1.021277 (2800 2900);
DISPLAY INVISIBLE (2800 2900);
FORCEADD OFFPAGE..3
(-425 3925);
FORCEPROP 2 LAST $XR1 102 
J 0
(-121 3925);
DISPLAY 0.638298 (-121 3925);
PAINT MONO (-121 3925);
FORCEPROP 2 LAST $XR0 53 
J 0
(-211 3925);
DISPLAY 0.638298 (-211 3925);
PAINT MONO (-211 3925);
FORCEPROP 2 LAST CDS_LIB standard
J 2
(-425 3925);
DISPLAY INVISIBLE (-425 3925);
FORCEPROP 1 LAST OFFPAGE TRUE
J 0
(-100 3800);
DISPLAY 0.872340 (-100 3800);
DISPLAY INVISIBLE (-100 3800);
FORCEPROP 1 LAST COMMENT_BODY TRUE
J 0
(-475 3825);
DISPLAY 0.872340 (-475 3825);
PAINT GREEN (-475 3825);
DISPLAY INVISIBLE (-475 3825);
FORCEPROP 2 LAST PATH I169
J 0
(-225 4000);
DISPLAY 1.021277 (-225 4000);
DISPLAY INVISIBLE (-225 4000);
FORCEADD OFFPAGE..1
(-3825 2650);
FORCEPROP 2 LAST $XR0 53 
J 0
(-4046 2650);
DISPLAY 0.638298 (-4046 2650);
PAINT MONO (-4046 2650);
FORCEPROP 2 LAST CDS_LIB standard
J 0
(-3825 2650);
PAINT MONO (-3825 2650);
DISPLAY INVISIBLE (-3825 2650);
FORCEPROP 1 LAST OFFPAGE TRUE
J 0
(-3500 2525);
DISPLAY 0.872340 (-3500 2525);
DISPLAY INVISIBLE (-3500 2525);
FORCEPROP 1 LAST COMMENT_BODY TRUE
J 0
(-3700 2550);
DISPLAY 0.872340 (-3700 2550);
PAINT GREEN (-3700 2550);
DISPLAY INVISIBLE (-3700 2550);
FORCEPROP 2 LAST PATH I17
J 0
(-3775 2725);
DISPLAY 1.021277 (-3775 2725);
DISPLAY INVISIBLE (-3775 2725);
FORCEADD TAP..1
(1500 3900);
FORCEPROP 3 LASTPIN (1450 3900) SIG_NAME M_C_CPU1_SA_DQS_DP<9>
J 0
(1460 3910);
DISPLAY 0.659574 (1460 3910);
PAINT MONO (1460 3910);
DISPLAY INVISIBLE (1460 3910);
FORCEPROP 1 LASTPIN (1450 3900) BN 9
J 0
(1438 3908);
DISPLAY 0.680851 (1438 3908);
PAINT GREEN (1438 3908);
FORCEPROP 2 LAST CDS_LIB standard
J 0
(1500 3900);
DISPLAY INVISIBLE (1500 3900);
FORCEPROP 1 LAST BODY_TYPE PLUMBING
J 0
(1500 3950);
DISPLAY 0.872340 (1500 3950);
PAINT GREEN (1500 3950);
DISPLAY INVISIBLE (1500 3950);
FORCEPROP 1 LAST HDL_TAP TRUE
J 0
(1825 3775);
DISPLAY 0.872340 (1825 3775);
DISPLAY INVISIBLE (1825 3775);
FORCEPROP 1 LAST PATH I170
J 0
(1498 3900);
DISPLAY 0.872340 (1498 3900);
PAINT GREEN (1498 3900);
DISPLAY INVISIBLE (1498 3900);
FORCEADD TAP..1
(1500 3800);
FORCEPROP 3 LASTPIN (1450 3800) SIG_NAME M_C_CPU1_SA_DQS_DP<8>
J 0
(1460 3810);
DISPLAY 0.659574 (1460 3810);
PAINT MONO (1460 3810);
DISPLAY INVISIBLE (1460 3810);
FORCEPROP 1 LASTPIN (1450 3800) BN 8
J 0
(1438 3808);
DISPLAY 0.680851 (1438 3808);
PAINT GREEN (1438 3808);
FORCEPROP 2 LAST CDS_LIB standard
J 0
(1500 3800);
DISPLAY INVISIBLE (1500 3800);
FORCEPROP 1 LAST BODY_TYPE PLUMBING
J 0
(1500 3850);
DISPLAY 0.872340 (1500 3850);
PAINT GREEN (1500 3850);
DISPLAY INVISIBLE (1500 3850);
FORCEPROP 1 LAST HDL_TAP TRUE
J 0
(1825 3675);
DISPLAY 0.872340 (1825 3675);
DISPLAY INVISIBLE (1825 3675);
FORCEPROP 1 LAST PATH I171
J 0
(1498 3800);
DISPLAY 0.872340 (1498 3800);
PAINT GREEN (1498 3800);
DISPLAY INVISIBLE (1498 3800);
FORCEADD TAP..1
(1675 3850);
FORCEPROP 3 LASTPIN (1625 3850) SIG_NAME M_C_CPU1_SA_DQS_DN<9>
J 0
(1635 3860);
DISPLAY 0.659574 (1635 3860);
PAINT MONO (1635 3860);
DISPLAY INVISIBLE (1635 3860);
FORCEPROP 1 LASTPIN (1625 3850) BN 9
J 0
(1613 3858);
DISPLAY 0.680851 (1613 3858);
PAINT GREEN (1613 3858);
FORCEPROP 2 LAST CDS_LIB standard
J 0
(1675 3850);
DISPLAY INVISIBLE (1675 3850);
FORCEPROP 1 LAST BODY_TYPE PLUMBING
J 0
(1675 3900);
DISPLAY 0.872340 (1675 3900);
PAINT GREEN (1675 3900);
DISPLAY INVISIBLE (1675 3900);
FORCEPROP 1 LAST HDL_TAP TRUE
J 0
(2000 3725);
DISPLAY 0.872340 (2000 3725);
DISPLAY INVISIBLE (2000 3725);
FORCEPROP 1 LAST PATH I172
J 0
(1673 3850);
DISPLAY 0.872340 (1673 3850);
PAINT GREEN (1673 3850);
DISPLAY INVISIBLE (1673 3850);
FORCEADD OFFPAGE..2
(2625 3925);
FORCEPROP 2 LAST $XR1 102 
J 0
(2904 3925);
DISPLAY 0.638298 (2904 3925);
PAINT MONO (2904 3925);
FORCEPROP 2 LAST $XR0 53 
J 0
(2814 3925);
DISPLAY 0.638298 (2814 3925);
PAINT MONO (2814 3925);
FORCEPROP 2 LAST CDS_LIB standard
J 0
(2625 3925);
PAINT MONO (2625 3925);
DISPLAY INVISIBLE (2625 3925);
FORCEPROP 1 LAST OFFPAGE TRUE
J 0
(2950 3800);
DISPLAY 1.170213 (2950 3800);
PAINT GREEN (2950 3800);
DISPLAY INVISIBLE (2950 3800);
FORCEPROP 1 LAST COMMENT_BODY TRUE
J 0
(2580 3830);
DISPLAY 1.170213 (2580 3830);
PAINT GREEN (2580 3830);
DISPLAY INVISIBLE (2580 3830);
FORCEPROP 2 LAST PATH I173
J 0
(2800 4000);
DISPLAY 1.021277 (2800 4000);
DISPLAY INVISIBLE (2800 4000);
FORCEADD OFFPAGE..2
(2625 3875);
FORCEPROP 2 LAST $XR1 102 
J 0
(2904 3875);
DISPLAY 0.638298 (2904 3875);
PAINT MONO (2904 3875);
FORCEPROP 2 LAST $XR0 53 
J 0
(2814 3875);
DISPLAY 0.638298 (2814 3875);
PAINT MONO (2814 3875);
FORCEPROP 2 LAST CDS_LIB standard
J 0
(2625 3875);
PAINT MONO (2625 3875);
DISPLAY INVISIBLE (2625 3875);
FORCEPROP 1 LAST OFFPAGE TRUE
J 0
(2950 3750);
DISPLAY 1.170213 (2950 3750);
PAINT GREEN (2950 3750);
DISPLAY INVISIBLE (2950 3750);
FORCEPROP 1 LAST COMMENT_BODY TRUE
J 0
(2580 3780);
DISPLAY 1.170213 (2580 3780);
PAINT GREEN (2580 3780);
DISPLAY INVISIBLE (2580 3780);
FORCEPROP 2 LAST PATH I174
J 0
(2800 3950);
DISPLAY 1.021277 (2800 3950);
DISPLAY INVISIBLE (2800 3950);
FORCEADD VCC_CORE..1
(3175 4450);
FORCEPROP 3 LASTPIN (3175 4400) SIG_NAME P12V_S3_AUX_CPU1_NVDIMM\g
J 0
(3185 4410);
DISPLAY 0.659574 (3185 4410);
PAINT MONO (3185 4410);
DISPLAY INVISIBLE (3185 4410);
FORCEPROP 1 LAST HDL_POWER P12V_S3_AUX_CPU1_NVDIMM
J 1
(3175 4500);
DISPLAY 1.148936 (3175 4500);
PAINT GREEN (3175 4500);
FORCEPROP 2 LAST CDS_LIB logical_power
J 0
(3175 4450);
PAINT MONO (3175 4450);
DISPLAY INVISIBLE (3175 4450);
FORCEPROP 1 LAST PATH I175
J 0
(3225 4475);
DISPLAY 0.872340 (3225 4475);
PAINT AQUA (3225 4475);
DISPLAY INVISIBLE (3225 4475);
FORCEADD SCONN288_ADR50017P087CC..3
(4025 2275);
FORCEPROP 1 LAST PART_NUMBER DFHST8FS460
J 0
(3570 4199);
DISPLAY 0.723404 (3570 4199);
PAINT GREEN (3570 4199);
DISPLAY INVISIBLE (3570 4199);
FORCEPROP 2 LAST PART_TYPE SMLF
J 0
(3575 4350);
DISPLAY 1.021277 (3575 4350);
FORCEPROP 2 LAST VALUE SCONN288_ADR50017-P087CC
J 0
(3575 4300);
DISPLAY 1.021277 (3575 4300);
FORCEPROP 1 LAST MATERIAL IO
J 0
(3570 4072);
DISPLAY 0.723404 (3570 4072);
PAINT GREEN (3570 4072);
FORCEPROP 1 LAST $LOCATION J22
J 0
(3575 4250);
DISPLAY 0.723404 (3575 4250);
PAINT GREEN (3575 4250);
FORCEPROP 0 LASTPIN (4625 650) $PN G1
J 0
(4635 660);
DISPLAY 0.680851 (4635 660);
PAINT MONO (4635 660);
FORCEPROP 0 LASTPIN (4625 600) $PN G2
J 0
(4635 610);
DISPLAY 0.680851 (4635 610);
PAINT MONO (4635 610);
FORCEPROP 0 LASTPIN (4625 550) $PN G3
J 0
(4635 560);
DISPLAY 0.680851 (4635 560);
PAINT MONO (4635 560);
FORCEPROP 0 LASTPIN (3425 3800) $PN 1
J 2
(3415 3810);
DISPLAY 0.680851 (3415 3810);
PAINT MONO (3415 3810);
FORCEPROP 0 LASTPIN (3425 3850) $PN 145
J 2
(3415 3860);
DISPLAY 0.680851 (3415 3860);
PAINT MONO (3415 3860);
FORCEPROP 0 LASTPIN (3425 3900) $PN 146
J 2
(3415 3910);
DISPLAY 0.680851 (3415 3910);
PAINT MONO (3415 3910);
FORCEPROP 0 LASTPIN (4625 750) $PN 6
J 0
(4635 760);
DISPLAY 0.680851 (4635 760);
PAINT MONO (4635 760);
FORCEPROP 0 LASTPIN (4625 800) $PN 8
J 0
(4635 810);
DISPLAY 0.680851 (4635 810);
PAINT MONO (4635 810);
FORCEPROP 0 LASTPIN (4625 850) $PN 10
J 0
(4635 860);
DISPLAY 0.680851 (4635 860);
PAINT MONO (4635 860);
FORCEPROP 0 LASTPIN (4625 900) $PN 13
J 0
(4635 910);
DISPLAY 0.680851 (4635 910);
PAINT MONO (4635 910);
FORCEPROP 0 LASTPIN (4625 950) $PN 15
J 0
(4635 960);
DISPLAY 0.680851 (4635 960);
PAINT MONO (4635 960);
FORCEPROP 0 LASTPIN (4625 1000) $PN 17
J 0
(4635 1010);
DISPLAY 0.680851 (4635 1010);
PAINT MONO (4635 1010);
FORCEPROP 0 LASTPIN (4625 1050) $PN 19
J 0
(4635 1060);
DISPLAY 0.680851 (4635 1060);
PAINT MONO (4635 1060);
FORCEPROP 0 LASTPIN (4625 1100) $PN 21
J 0
(4635 1110);
DISPLAY 0.680851 (4635 1110);
PAINT MONO (4635 1110);
FORCEPROP 0 LASTPIN (4625 1150) $PN 24
J 0
(4635 1160);
DISPLAY 0.680851 (4635 1160);
PAINT MONO (4635 1160);
FORCEPROP 0 LASTPIN (4625 1200) $PN 26
J 0
(4635 1210);
DISPLAY 0.680851 (4635 1210);
PAINT MONO (4635 1210);
FORCEPROP 0 LASTPIN (4625 1250) $PN 28
J 0
(4635 1260);
DISPLAY 0.680851 (4635 1260);
PAINT MONO (4635 1260);
FORCEPROP 0 LASTPIN (4625 1300) $PN 30
J 0
(4635 1310);
DISPLAY 0.680851 (4635 1310);
PAINT MONO (4635 1310);
FORCEPROP 0 LASTPIN (4625 1350) $PN 32
J 0
(4635 1360);
DISPLAY 0.680851 (4635 1360);
PAINT MONO (4635 1360);
FORCEPROP 0 LASTPIN (4625 1400) $PN 35
J 0
(4635 1410);
DISPLAY 0.680851 (4635 1410);
PAINT MONO (4635 1410);
FORCEPROP 0 LASTPIN (4625 1450) $PN 37
J 0
(4635 1460);
DISPLAY 0.680851 (4635 1460);
PAINT MONO (4635 1460);
FORCEPROP 0 LASTPIN (4625 1500) $PN 39
J 0
(4635 1510);
DISPLAY 0.680851 (4635 1510);
PAINT MONO (4635 1510);
FORCEPROP 0 LASTPIN (4625 1550) $PN 41
J 0
(4635 1560);
DISPLAY 0.680851 (4635 1560);
PAINT MONO (4635 1560);
FORCEPROP 0 LASTPIN (4625 1600) $PN 43
J 0
(4635 1610);
DISPLAY 0.680851 (4635 1610);
PAINT MONO (4635 1610);
FORCEPROP 0 LASTPIN (4625 1650) $PN 46
J 0
(4635 1660);
DISPLAY 0.680851 (4635 1660);
PAINT MONO (4635 1660);
FORCEPROP 0 LASTPIN (4625 1700) $PN 48
J 0
(4635 1710);
DISPLAY 0.680851 (4635 1710);
PAINT MONO (4635 1710);
FORCEPROP 0 LASTPIN (4625 1750) $PN 50
J 0
(4635 1760);
DISPLAY 0.680851 (4635 1760);
PAINT MONO (4635 1760);
FORCEPROP 0 LASTPIN (4625 1800) $PN 52
J 0
(4635 1810);
DISPLAY 0.680851 (4635 1810);
PAINT MONO (4635 1810);
FORCEPROP 0 LASTPIN (4625 1850) $PN 54
J 0
(4635 1860);
DISPLAY 0.680851 (4635 1860);
PAINT MONO (4635 1860);
FORCEPROP 0 LASTPIN (4625 1900) $PN 57
J 0
(4635 1910);
DISPLAY 0.680851 (4635 1910);
PAINT MONO (4635 1910);
FORCEPROP 0 LASTPIN (4625 1950) $PN 59
J 0
(4635 1960);
DISPLAY 0.680851 (4635 1960);
PAINT MONO (4635 1960);
FORCEPROP 0 LASTPIN (4625 2000) $PN 61
J 0
(4635 2010);
DISPLAY 0.680851 (4635 2010);
PAINT MONO (4635 2010);
FORCEPROP 0 LASTPIN (4625 2050) $PN 63
J 0
(4635 2060);
DISPLAY 0.680851 (4635 2060);
PAINT MONO (4635 2060);
FORCEPROP 0 LASTPIN (4625 2100) $PN 65
J 0
(4635 2110);
DISPLAY 0.680851 (4635 2110);
PAINT MONO (4635 2110);
FORCEPROP 0 LASTPIN (4625 2150) $PN 67
J 0
(4635 2160);
DISPLAY 0.680851 (4635 2160);
PAINT MONO (4635 2160);
FORCEPROP 0 LASTPIN (4625 2200) $PN 69
J 0
(4635 2210);
DISPLAY 0.680851 (4635 2210);
PAINT MONO (4635 2210);
FORCEPROP 0 LASTPIN (4625 2250) $PN 71
J 0
(4635 2260);
DISPLAY 0.680851 (4635 2260);
PAINT MONO (4635 2260);
FORCEPROP 0 LASTPIN (4625 2300) $PN 73
J 0
(4635 2310);
DISPLAY 0.680851 (4635 2310);
PAINT MONO (4635 2310);
FORCEPROP 0 LASTPIN (4625 2350) $PN 75
J 0
(4635 2360);
DISPLAY 0.680851 (4635 2360);
PAINT MONO (4635 2360);
FORCEPROP 0 LASTPIN (4625 2400) $PN 77
J 0
(4635 2410);
DISPLAY 0.680851 (4635 2410);
PAINT MONO (4635 2410);
FORCEPROP 0 LASTPIN (4625 2450) $PN 79
J 0
(4635 2460);
DISPLAY 0.680851 (4635 2460);
PAINT MONO (4635 2460);
FORCEPROP 0 LASTPIN (4625 2500) $PN 81
J 0
(4635 2510);
DISPLAY 0.680851 (4635 2510);
PAINT MONO (4635 2510);
FORCEPROP 0 LASTPIN (4625 2550) $PN 83
J 0
(4635 2560);
DISPLAY 0.680851 (4635 2560);
PAINT MONO (4635 2560);
FORCEPROP 0 LASTPIN (4625 2600) $PN 85
J 0
(4635 2610);
DISPLAY 0.680851 (4635 2610);
PAINT MONO (4635 2610);
FORCEPROP 0 LASTPIN (4625 2650) $PN 88
J 0
(4635 2660);
DISPLAY 0.680851 (4635 2660);
PAINT MONO (4635 2660);
FORCEPROP 0 LASTPIN (4625 2700) $PN 90
J 0
(4635 2710);
DISPLAY 0.680851 (4635 2710);
PAINT MONO (4635 2710);
FORCEPROP 0 LASTPIN (4625 2750) $PN 92
J 0
(4635 2760);
DISPLAY 0.680851 (4635 2760);
PAINT MONO (4635 2760);
FORCEPROP 0 LASTPIN (4625 2800) $PN 95
J 0
(4635 2810);
DISPLAY 0.680851 (4635 2810);
PAINT MONO (4635 2810);
FORCEPROP 0 LASTPIN (4625 2850) $PN 97
J 0
(4635 2860);
DISPLAY 0.680851 (4635 2860);
PAINT MONO (4635 2860);
FORCEPROP 0 LASTPIN (4625 2900) $PN 99
J 0
(4635 2910);
DISPLAY 0.680851 (4635 2910);
PAINT MONO (4635 2910);
FORCEPROP 0 LASTPIN (4625 2950) $PN 101
J 0
(4635 2960);
DISPLAY 0.680851 (4635 2960);
PAINT MONO (4635 2960);
FORCEPROP 0 LASTPIN (4625 3000) $PN 103
J 0
(4635 3010);
DISPLAY 0.680851 (4635 3010);
PAINT MONO (4635 3010);
FORCEPROP 0 LASTPIN (4625 3050) $PN 106
J 0
(4635 3060);
DISPLAY 0.680851 (4635 3060);
PAINT MONO (4635 3060);
FORCEPROP 0 LASTPIN (4625 3100) $PN 108
J 0
(4635 3110);
DISPLAY 0.680851 (4635 3110);
PAINT MONO (4635 3110);
FORCEPROP 0 LASTPIN (4625 3150) $PN 110
J 0
(4635 3160);
DISPLAY 0.680851 (4635 3160);
PAINT MONO (4635 3160);
FORCEPROP 0 LASTPIN (4625 3200) $PN 112
J 0
(4635 3210);
DISPLAY 0.680851 (4635 3210);
PAINT MONO (4635 3210);
FORCEPROP 0 LASTPIN (4625 3250) $PN 114
J 0
(4635 3260);
DISPLAY 0.680851 (4635 3260);
PAINT MONO (4635 3260);
FORCEPROP 0 LASTPIN (4625 3300) $PN 117
J 0
(4635 3310);
DISPLAY 0.680851 (4635 3310);
PAINT MONO (4635 3310);
FORCEPROP 0 LASTPIN (4625 3350) $PN 119
J 0
(4635 3360);
DISPLAY 0.680851 (4635 3360);
PAINT MONO (4635 3360);
FORCEPROP 0 LASTPIN (4625 3400) $PN 121
J 0
(4635 3410);
DISPLAY 0.680851 (4635 3410);
PAINT MONO (4635 3410);
FORCEPROP 0 LASTPIN (4625 3450) $PN 123
J 0
(4635 3460);
DISPLAY 0.680851 (4635 3460);
PAINT MONO (4635 3460);
FORCEPROP 0 LASTPIN (4625 3500) $PN 125
J 0
(4635 3510);
DISPLAY 0.680851 (4635 3510);
PAINT MONO (4635 3510);
FORCEPROP 0 LASTPIN (4625 3550) $PN 128
J 0
(4635 3560);
DISPLAY 0.680851 (4635 3560);
PAINT MONO (4635 3560);
FORCEPROP 0 LASTPIN (4625 3600) $PN 130
J 0
(4635 3610);
DISPLAY 0.680851 (4635 3610);
PAINT MONO (4635 3610);
FORCEPROP 0 LASTPIN (4625 3650) $PN 132
J 0
(4635 3660);
DISPLAY 0.680851 (4635 3660);
PAINT MONO (4635 3660);
FORCEPROP 0 LASTPIN (4625 3700) $PN 134
J 0
(4635 3710);
DISPLAY 0.680851 (4635 3710);
PAINT MONO (4635 3710);
FORCEPROP 0 LASTPIN (4625 3750) $PN 136
J 0
(4635 3760);
DISPLAY 0.680851 (4635 3760);
PAINT MONO (4635 3760);
FORCEPROP 0 LASTPIN (4625 3800) $PN 139
J 0
(4635 3810);
DISPLAY 0.680851 (4635 3810);
PAINT MONO (4635 3810);
FORCEPROP 0 LASTPIN (4625 3850) $PN 141
J 0
(4635 3860);
DISPLAY 0.680851 (4635 3860);
PAINT MONO (4635 3860);
FORCEPROP 0 LASTPIN (4625 3900) $PN 143
J 0
(4635 3910);
DISPLAY 0.680851 (4635 3910);
PAINT MONO (4635 3910);
FORCEPROP 0 LASTPIN (3425 650) $PN 151
J 2
(3415 660);
DISPLAY 0.680851 (3415 660);
PAINT MONO (3415 660);
FORCEPROP 0 LASTPIN (3425 700) $PN 153
J 2
(3415 710);
DISPLAY 0.680851 (3415 710);
PAINT MONO (3415 710);
FORCEPROP 0 LASTPIN (3425 750) $PN 155
J 2
(3415 760);
DISPLAY 0.680851 (3415 760);
PAINT MONO (3415 760);
FORCEPROP 0 LASTPIN (3425 800) $PN 158
J 2
(3415 810);
DISPLAY 0.680851 (3415 810);
PAINT MONO (3415 810);
FORCEPROP 0 LASTPIN (3425 850) $PN 160
J 2
(3415 860);
DISPLAY 0.680851 (3415 860);
PAINT MONO (3415 860);
FORCEPROP 0 LASTPIN (3425 900) $PN 162
J 2
(3415 910);
DISPLAY 0.680851 (3415 910);
PAINT MONO (3415 910);
FORCEPROP 0 LASTPIN (3425 950) $PN 164
J 2
(3415 960);
DISPLAY 0.680851 (3415 960);
PAINT MONO (3415 960);
FORCEPROP 0 LASTPIN (3425 1000) $PN 166
J 2
(3415 1010);
DISPLAY 0.680851 (3415 1010);
PAINT MONO (3415 1010);
FORCEPROP 0 LASTPIN (3425 1050) $PN 169
J 2
(3415 1060);
DISPLAY 0.680851 (3415 1060);
PAINT MONO (3415 1060);
FORCEPROP 0 LASTPIN (3425 1100) $PN 171
J 2
(3415 1110);
DISPLAY 0.680851 (3415 1110);
PAINT MONO (3415 1110);
FORCEPROP 0 LASTPIN (3425 1150) $PN 173
J 2
(3415 1160);
DISPLAY 0.680851 (3415 1160);
PAINT MONO (3415 1160);
FORCEPROP 0 LASTPIN (3425 1200) $PN 175
J 2
(3415 1210);
DISPLAY 0.680851 (3415 1210);
PAINT MONO (3415 1210);
FORCEPROP 0 LASTPIN (3425 1250) $PN 177
J 2
(3415 1260);
DISPLAY 0.680851 (3415 1260);
PAINT MONO (3415 1260);
FORCEPROP 0 LASTPIN (3425 1300) $PN 180
J 2
(3415 1310);
DISPLAY 0.680851 (3415 1310);
PAINT MONO (3415 1310);
FORCEPROP 0 LASTPIN (3425 1350) $PN 182
J 2
(3415 1360);
DISPLAY 0.680851 (3415 1360);
PAINT MONO (3415 1360);
FORCEPROP 0 LASTPIN (3425 1400) $PN 184
J 2
(3415 1410);
DISPLAY 0.680851 (3415 1410);
PAINT MONO (3415 1410);
FORCEPROP 0 LASTPIN (3425 1450) $PN 186
J 2
(3415 1460);
DISPLAY 0.680851 (3415 1460);
PAINT MONO (3415 1460);
FORCEPROP 0 LASTPIN (3425 1500) $PN 188
J 2
(3415 1510);
DISPLAY 0.680851 (3415 1510);
PAINT MONO (3415 1510);
FORCEPROP 0 LASTPIN (3425 1550) $PN 191
J 2
(3415 1560);
DISPLAY 0.680851 (3415 1560);
PAINT MONO (3415 1560);
FORCEPROP 0 LASTPIN (3425 1600) $PN 193
J 2
(3415 1610);
DISPLAY 0.680851 (3415 1610);
PAINT MONO (3415 1610);
FORCEPROP 0 LASTPIN (3425 1650) $PN 195
J 2
(3415 1660);
DISPLAY 0.680851 (3415 1660);
PAINT MONO (3415 1660);
FORCEPROP 0 LASTPIN (3425 1700) $PN 197
J 2
(3415 1710);
DISPLAY 0.680851 (3415 1710);
PAINT MONO (3415 1710);
FORCEPROP 0 LASTPIN (3425 1750) $PN 199
J 2
(3415 1760);
DISPLAY 0.680851 (3415 1760);
PAINT MONO (3415 1760);
FORCEPROP 0 LASTPIN (3425 1800) $PN 202
J 2
(3415 1810);
DISPLAY 0.680851 (3415 1810);
PAINT MONO (3415 1810);
FORCEPROP 0 LASTPIN (3425 1850) $PN 204
J 2
(3415 1860);
DISPLAY 0.680851 (3415 1860);
PAINT MONO (3415 1860);
FORCEPROP 0 LASTPIN (3425 1900) $PN 206
J 2
(3415 1910);
DISPLAY 0.680851 (3415 1910);
PAINT MONO (3415 1910);
FORCEPROP 0 LASTPIN (3425 1950) $PN 208
J 2
(3415 1960);
DISPLAY 0.680851 (3415 1960);
PAINT MONO (3415 1960);
FORCEPROP 0 LASTPIN (3425 2000) $PN 210
J 2
(3415 2010);
DISPLAY 0.680851 (3415 2010);
PAINT MONO (3415 2010);
FORCEPROP 0 LASTPIN (3425 2050) $PN 212
J 2
(3415 2060);
DISPLAY 0.680851 (3415 2060);
PAINT MONO (3415 2060);
FORCEPROP 0 LASTPIN (3425 2100) $PN 214
J 2
(3415 2110);
DISPLAY 0.680851 (3415 2110);
PAINT MONO (3415 2110);
FORCEPROP 0 LASTPIN (3425 2150) $PN 216
J 2
(3415 2160);
DISPLAY 0.680851 (3415 2160);
PAINT MONO (3415 2160);
FORCEPROP 0 LASTPIN (3425 2200) $PN 219
J 2
(3415 2210);
DISPLAY 0.680851 (3415 2210);
PAINT MONO (3415 2210);
FORCEPROP 0 LASTPIN (3425 2250) $PN 222
J 2
(3415 2260);
DISPLAY 0.680851 (3415 2260);
PAINT MONO (3415 2260);
FORCEPROP 0 LASTPIN (3425 2300) $PN 224
J 2
(3415 2310);
DISPLAY 0.680851 (3415 2310);
PAINT MONO (3415 2310);
FORCEPROP 0 LASTPIN (3425 2350) $PN 226
J 2
(3415 2360);
DISPLAY 0.680851 (3415 2360);
PAINT MONO (3415 2360);
FORCEPROP 0 LASTPIN (3425 2400) $PN 228
J 2
(3415 2410);
DISPLAY 0.680851 (3415 2410);
PAINT MONO (3415 2410);
FORCEPROP 0 LASTPIN (3425 2450) $PN 230
J 2
(3415 2460);
DISPLAY 0.680851 (3415 2460);
PAINT MONO (3415 2460);
FORCEPROP 0 LASTPIN (3425 2500) $PN 233
J 2
(3415 2510);
DISPLAY 0.680851 (3415 2510);
PAINT MONO (3415 2510);
FORCEPROP 0 LASTPIN (3425 2550) $PN 235
J 2
(3415 2560);
DISPLAY 0.680851 (3415 2560);
PAINT MONO (3415 2560);
FORCEPROP 0 LASTPIN (3425 2600) $PN 237
J 2
(3415 2610);
DISPLAY 0.680851 (3415 2610);
PAINT MONO (3415 2610);
FORCEPROP 0 LASTPIN (3425 2650) $PN 240
J 2
(3415 2660);
DISPLAY 0.680851 (3415 2660);
PAINT MONO (3415 2660);
FORCEPROP 0 LASTPIN (3425 2700) $PN 242
J 2
(3415 2710);
DISPLAY 0.680851 (3415 2710);
PAINT MONO (3415 2710);
FORCEPROP 0 LASTPIN (3425 2750) $PN 244
J 2
(3415 2760);
DISPLAY 0.680851 (3415 2760);
PAINT MONO (3415 2760);
FORCEPROP 0 LASTPIN (3425 2800) $PN 246
J 2
(3415 2810);
DISPLAY 0.680851 (3415 2810);
PAINT MONO (3415 2810);
FORCEPROP 0 LASTPIN (3425 2850) $PN 248
J 2
(3415 2860);
DISPLAY 0.680851 (3415 2860);
PAINT MONO (3415 2860);
FORCEPROP 0 LASTPIN (3425 2900) $PN 251
J 2
(3415 2910);
DISPLAY 0.680851 (3415 2910);
PAINT MONO (3415 2910);
FORCEPROP 0 LASTPIN (3425 2950) $PN 253
J 2
(3415 2960);
DISPLAY 0.680851 (3415 2960);
PAINT MONO (3415 2960);
FORCEPROP 0 LASTPIN (3425 3000) $PN 255
J 2
(3415 3010);
DISPLAY 0.680851 (3415 3010);
PAINT MONO (3415 3010);
FORCEPROP 0 LASTPIN (3425 3050) $PN 257
J 2
(3415 3060);
DISPLAY 0.680851 (3415 3060);
PAINT MONO (3415 3060);
FORCEPROP 0 LASTPIN (3425 3100) $PN 259
J 2
(3415 3110);
DISPLAY 0.680851 (3415 3110);
PAINT MONO (3415 3110);
FORCEPROP 0 LASTPIN (3425 3150) $PN 262
J 2
(3415 3160);
DISPLAY 0.680851 (3415 3160);
PAINT MONO (3415 3160);
FORCEPROP 0 LASTPIN (3425 3200) $PN 264
J 2
(3415 3210);
DISPLAY 0.680851 (3415 3210);
PAINT MONO (3415 3210);
FORCEPROP 0 LASTPIN (3425 3250) $PN 266
J 2
(3415 3260);
DISPLAY 0.680851 (3415 3260);
PAINT MONO (3415 3260);
FORCEPROP 0 LASTPIN (3425 3300) $PN 268
J 2
(3415 3310);
DISPLAY 0.680851 (3415 3310);
PAINT MONO (3415 3310);
FORCEPROP 0 LASTPIN (3425 3350) $PN 270
J 2
(3415 3360);
DISPLAY 0.680851 (3415 3360);
PAINT MONO (3415 3360);
FORCEPROP 0 LASTPIN (3425 3400) $PN 273
J 2
(3415 3410);
DISPLAY 0.680851 (3415 3410);
PAINT MONO (3415 3410);
FORCEPROP 0 LASTPIN (3425 3450) $PN 275
J 2
(3415 3460);
DISPLAY 0.680851 (3415 3460);
PAINT MONO (3415 3460);
FORCEPROP 0 LASTPIN (3425 3500) $PN 277
J 2
(3415 3510);
DISPLAY 0.680851 (3415 3510);
PAINT MONO (3415 3510);
FORCEPROP 0 LASTPIN (3425 3550) $PN 279
J 2
(3415 3560);
DISPLAY 0.680851 (3415 3560);
PAINT MONO (3415 3560);
FORCEPROP 0 LASTPIN (3425 3600) $PN 281
J 2
(3415 3610);
DISPLAY 0.680851 (3415 3610);
PAINT MONO (3415 3610);
FORCEPROP 0 LASTPIN (3425 3650) $PN 284
J 2
(3415 3660);
DISPLAY 0.680851 (3415 3660);
PAINT MONO (3415 3660);
FORCEPROP 0 LASTPIN (3425 3700) $PN 286
J 2
(3415 3710);
DISPLAY 0.680851 (3415 3710);
PAINT MONO (3415 3710);
FORCEPROP 0 LASTPIN (3425 3750) $PN 288
J 2
(3415 3760);
DISPLAY 0.680851 (3415 3760);
PAINT MONO (3415 3760);
FORCEPROP 1 LAST NEEDS_NO_SIZE TRUE
J 0
(4025 2275);
DISPLAY 0.723404 (4025 2275);
PAINT GREEN (4025 2275);
DISPLAY INVISIBLE (4025 2275);
FORCEPROP 1 LAST CDS_LMAN_SYM_OUTLINE -450,1775,450,-1775
J 0
(4025 2275);
DISPLAY 0.468085 (4025 2275);
PAINT GREEN (4025 2275);
DISPLAY INVISIBLE (4025 2275);
FORCEPROP 2 LAST CDS_LIB pure_quanta
J 0
(4025 2275);
DISPLAY INVISIBLE (4025 2275);
FORCEPROP 1 LAST PATH I176
J 0
(4025 2275);
DISPLAY 0.723404 (4025 2275);
PAINT GREEN (4025 2275);
DISPLAY INVISIBLE (4025 2275);
FORCEPROP 2 LAST CDS_LOCATION J22
J 0
(3575 4400);
DISPLAY 1.021277 (3575 4400);
DISPLAY INVISIBLE (3575 4400);
FORCEPROP 0 LAST $SEC 3
J 0
(3575 4400);
DISPLAY 0.680851 (3575 4400);
PAINT MONO (3575 4400);
DISPLAY INVISIBLE (3575 4400);
FORCEPROP 2 LAST CDS_SEC 3
J 0
(3575 4400);
DISPLAY 1.021277 (3575 4400);
DISPLAY INVISIBLE (3575 4400);
FORCEADD UNIVERSAL_GND..1
(4875 200);
FORCEPROP 3 LASTPIN (4875 250) SIG_NAME GND\g
J 0
(4885 260);
DISPLAY 0.659574 (4885 260);
PAINT MONO (4885 260);
DISPLAY INVISIBLE (4885 260);
FORCEPROP 1 LAST PATH I177
J 0
(4950 200);
DISPLAY 0.872340 (4950 200);
PAINT AQUA (4950 200);
DISPLAY INVISIBLE (4950 200);
FORCEPROP 1 LAST HDL_POWER GND
J 1
(4900 125);
DISPLAY 0.872340 (4900 125);
PAINT GREEN (4900 125);
DISPLAY INVISIBLE (4900 125);
FORCEPROP 2 LAST CDS_LIB logical_power
J 0
(4875 200);
PAINT MONO (4875 200);
DISPLAY INVISIBLE (4875 200);
FORCEADD SCONN288_ADR50017P087CC..2
(600 2900);
FORCEPROP 1 LAST PART_NUMBER DFHST8FS460
J 0
(-5 4188);
DISPLAY 0.723404 (-5 4188);
PAINT GREEN (-5 4188);
DISPLAY INVISIBLE (-5 4188);
FORCEPROP 2 LAST PART_TYPE SMLF
J 0
(0 4425);
DISPLAY 1.021277 (0 4425);
FORCEPROP 1 LAST MATERIAL IO
J 0
(-5 4061);
DISPLAY 0.723404 (-5 4061);
PAINT GREEN (-5 4061);
FORCEPROP 2 LAST VALUE SCONN288_ADR50017-P087CC
J 0
(0 4375);
DISPLAY 1.021277 (0 4375);
FORCEPROP 1 LAST LOCATION J22
J 0
(-5 4335);
DISPLAY 0.723404 (-5 4335);
PAINT GREEN (-5 4335);
FORCEPROP 0 LASTPIN (1350 2950) $PN 12
J 0
(1360 2960);
DISPLAY 0.680851 (1360 2960);
PAINT MONO (1360 2960);
FORCEPROP 0 LASTPIN (1350 3000) $PN 11
J 0
(1360 3010);
DISPLAY 0.680851 (1360 3010);
PAINT MONO (1360 3010);
FORCEPROP 0 LASTPIN (1350 1900) $PN 105
J 0
(1360 1910);
DISPLAY 0.680851 (1360 1910);
PAINT MONO (1360 1910);
FORCEPROP 0 LASTPIN (1350 1950) $PN 104
J 0
(1360 1960);
DISPLAY 0.680851 (1360 1960);
PAINT MONO (1360 1960);
FORCEPROP 0 LASTPIN (1350 3050) $PN 23
J 0
(1360 3060);
DISPLAY 0.680851 (1360 3060);
PAINT MONO (1360 3060);
FORCEPROP 0 LASTPIN (1350 3100) $PN 22
J 0
(1360 3110);
DISPLAY 0.680851 (1360 3110);
PAINT MONO (1360 3110);
FORCEPROP 0 LASTPIN (1350 2000) $PN 116
J 0
(1360 2010);
DISPLAY 0.680851 (1360 2010);
PAINT MONO (1360 2010);
FORCEPROP 0 LASTPIN (1350 2050) $PN 115
J 0
(1360 2060);
DISPLAY 0.680851 (1360 2060);
PAINT MONO (1360 2060);
FORCEPROP 0 LASTPIN (1350 3150) $PN 34
J 0
(1360 3160);
DISPLAY 0.680851 (1360 3160);
PAINT MONO (1360 3160);
FORCEPROP 0 LASTPIN (1350 3200) $PN 33
J 0
(1360 3210);
DISPLAY 0.680851 (1360 3210);
PAINT MONO (1360 3210);
FORCEPROP 0 LASTPIN (1350 2100) $PN 127
J 0
(1360 2110);
DISPLAY 0.680851 (1360 2110);
PAINT MONO (1360 2110);
FORCEPROP 0 LASTPIN (1350 2150) $PN 126
J 0
(1360 2160);
DISPLAY 0.680851 (1360 2160);
PAINT MONO (1360 2160);
FORCEPROP 0 LASTPIN (1350 3250) $PN 45
J 0
(1360 3260);
DISPLAY 0.680851 (1360 3260);
PAINT MONO (1360 3260);
FORCEPROP 0 LASTPIN (1350 3300) $PN 44
J 0
(1360 3310);
DISPLAY 0.680851 (1360 3310);
PAINT MONO (1360 3310);
FORCEPROP 0 LASTPIN (1350 2200) $PN 138
J 0
(1360 2210);
DISPLAY 0.680851 (1360 2210);
PAINT MONO (1360 2210);
FORCEPROP 0 LASTPIN (1350 2250) $PN 137
J 0
(1360 2260);
DISPLAY 0.680851 (1360 2260);
PAINT MONO (1360 2260);
FORCEPROP 0 LASTPIN (1350 3350) $PN 56
J 0
(1360 3360);
DISPLAY 0.680851 (1360 3360);
PAINT MONO (1360 3360);
FORCEPROP 0 LASTPIN (1350 3400) $PN 55
J 0
(1360 3410);
DISPLAY 0.680851 (1360 3410);
PAINT MONO (1360 3410);
FORCEPROP 0 LASTPIN (1350 2300) $PN 238
J 0
(1360 2310);
DISPLAY 0.680851 (1360 2310);
PAINT MONO (1360 2310);
FORCEPROP 0 LASTPIN (1350 2350) $PN 239
J 0
(1360 2360);
DISPLAY 0.680851 (1360 2360);
PAINT MONO (1360 2360);
FORCEPROP 0 LASTPIN (1350 3450) $PN 156
J 0
(1360 3460);
DISPLAY 0.680851 (1360 3460);
PAINT MONO (1360 3460);
FORCEPROP 0 LASTPIN (1350 3500) $PN 157
J 0
(1360 3510);
DISPLAY 0.680851 (1360 3510);
PAINT MONO (1360 3510);
FORCEPROP 0 LASTPIN (1350 2400) $PN 249
J 0
(1360 2410);
DISPLAY 0.680851 (1360 2410);
PAINT MONO (1360 2410);
FORCEPROP 0 LASTPIN (1350 2450) $PN 250
J 0
(1360 2460);
DISPLAY 0.680851 (1360 2460);
PAINT MONO (1360 2460);
FORCEPROP 0 LASTPIN (1350 3550) $PN 167
J 0
(1360 3560);
DISPLAY 0.680851 (1360 3560);
PAINT MONO (1360 3560);
FORCEPROP 0 LASTPIN (1350 3600) $PN 168
J 0
(1360 3610);
DISPLAY 0.680851 (1360 3610);
PAINT MONO (1360 3610);
FORCEPROP 0 LASTPIN (1350 2500) $PN 260
J 0
(1360 2510);
DISPLAY 0.680851 (1360 2510);
PAINT MONO (1360 2510);
FORCEPROP 0 LASTPIN (1350 2550) $PN 261
J 0
(1360 2560);
DISPLAY 0.680851 (1360 2560);
PAINT MONO (1360 2560);
FORCEPROP 0 LASTPIN (1350 3650) $PN 178
J 0
(1360 3660);
DISPLAY 0.680851 (1360 3660);
PAINT MONO (1360 3660);
FORCEPROP 0 LASTPIN (1350 3700) $PN 179
J 0
(1360 3710);
DISPLAY 0.680851 (1360 3710);
PAINT MONO (1360 3710);
FORCEPROP 0 LASTPIN (1350 2600) $PN 271
J 0
(1360 2610);
DISPLAY 0.680851 (1360 2610);
PAINT MONO (1360 2610);
FORCEPROP 0 LASTPIN (1350 2650) $PN 272
J 0
(1360 2660);
DISPLAY 0.680851 (1360 2660);
PAINT MONO (1360 2660);
FORCEPROP 0 LASTPIN (1350 3750) $PN 189
J 0
(1360 3760);
DISPLAY 0.680851 (1360 3760);
PAINT MONO (1360 3760);
FORCEPROP 0 LASTPIN (1350 3800) $PN 190
J 0
(1360 3810);
DISPLAY 0.680851 (1360 3810);
PAINT MONO (1360 3810);
FORCEPROP 0 LASTPIN (1350 2700) $PN 282
J 0
(1360 2710);
DISPLAY 0.680851 (1360 2710);
PAINT MONO (1360 2710);
FORCEPROP 0 LASTPIN (1350 2750) $PN 283
J 0
(1360 2760);
DISPLAY 0.680851 (1360 2760);
PAINT MONO (1360 2760);
FORCEPROP 0 LASTPIN (1350 3850) $PN 200
J 0
(1360 3860);
DISPLAY 0.680851 (1360 3860);
PAINT MONO (1360 3860);
FORCEPROP 0 LASTPIN (1350 3900) $PN 201
J 0
(1360 3910);
DISPLAY 0.680851 (1360 3910);
PAINT MONO (1360 3910);
FORCEPROP 0 LASTPIN (1350 2800) $PN 94
J 0
(1360 2810);
DISPLAY 0.680851 (1360 2810);
PAINT MONO (1360 2810);
FORCEPROP 0 LASTPIN (1350 2850) $PN 93
J 0
(1360 2860);
DISPLAY 0.680851 (1360 2860);
PAINT MONO (1360 2860);
FORCEPROP 1 LAST NEEDS_NO_SIZE TRUE
J 0
(600 2900);
DISPLAY 0.723404 (600 2900);
PAINT GREEN (600 2900);
DISPLAY INVISIBLE (600 2900);
FORCEPROP 1 LAST CDS_LMAN_SYM_OUTLINE -600,1150,600,-1150
J 0
(600 2900);
DISPLAY 0.468085 (600 2900);
PAINT GREEN (600 2900);
DISPLAY INVISIBLE (600 2900);
FORCEPROP 2 LAST CDS_LIB pure_quanta
J 0
(600 2900);
DISPLAY INVISIBLE (600 2900);
FORCEPROP 1 LAST PATH I178
J 0
(600 2900);
DISPLAY 0.723404 (600 2900);
PAINT GREEN (600 2900);
DISPLAY INVISIBLE (600 2900);
FORCEPROP 0 LAST $SEC 2
J 0
(0 4475);
DISPLAY 0.680851 (0 4475);
PAINT MONO (0 4475);
DISPLAY INVISIBLE (0 4475);
FORCEPROP 0 LAST CDS_SEC 2
J 0
(0 4475);
DISPLAY 1.021277 (0 4475);
DISPLAY INVISIBLE (0 4475);
FORCEADD OFFPAGE..1
(-2650 1125);
FORCEPROP 2 LAST $XR7 105 
J 0
(-3682 1125);
DISPLAY 0.638298 (-3682 1125);
PAINT MONO (-3682 1125);
FORCEPROP 2 LAST $XR6 104 
J 0
(-3562 1125);
DISPLAY 0.638298 (-3562 1125);
PAINT MONO (-3562 1125);
FORCEPROP 2 LAST $XR5 102 
J 0
(-3442 1125);
DISPLAY 0.638298 (-3442 1125);
PAINT MONO (-3442 1125);
FORCEPROP 2 LAST $XR4 101 
J 0
(-3322 1125);
DISPLAY 0.638298 (-3322 1125);
PAINT MONO (-3322 1125);
FORCEPROP 2 LAST $XR3 100 
J 0
(-3202 1125);
DISPLAY 0.638298 (-3202 1125);
PAINT MONO (-3202 1125);
FORCEPROP 2 LAST $XR2 99 
J 0
(-3082 1125);
DISPLAY 0.638298 (-3082 1125);
PAINT MONO (-3082 1125);
FORCEPROP 2 LAST $XR1 98 
J 0
(-2992 1125);
DISPLAY 0.638298 (-2992 1125);
PAINT MONO (-2992 1125);
FORCEPROP 2 LAST $XR0 230 
J 0
(-2902 1125);
DISPLAY 0.638298 (-2902 1125);
PAINT MONO (-2902 1125);
FORCEPROP 2 LAST CDS_LIB standard
J 2
(-2650 1125);
DISPLAY INVISIBLE (-2650 1125);
FORCEPROP 1 LAST OFFPAGE TRUE
J 0
(-2325 1000);
DISPLAY 0.872340 (-2325 1000);
DISPLAY INVISIBLE (-2325 1000);
FORCEPROP 1 LAST COMMENT_BODY TRUE
J 0
(-2525 1025);
DISPLAY 0.872340 (-2525 1025);
PAINT GREEN (-2525 1025);
DISPLAY INVISIBLE (-2525 1025);
FORCEPROP 2 LAST PATH I179
J 2
(-2825 1200);
DISPLAY 1.021277 (-2825 1200);
DISPLAY INVISIBLE (-2825 1200);
FORCEADD OFFPAGE..1
(-3825 2800);
FORCEPROP 2 LAST $XR0 53 
J 0
(-4046 2800);
DISPLAY 0.638298 (-4046 2800);
PAINT MONO (-4046 2800);
FORCEPROP 2 LAST CDS_LIB standard
J 0
(-3825 2800);
PAINT MONO (-3825 2800);
DISPLAY INVISIBLE (-3825 2800);
FORCEPROP 1 LAST OFFPAGE TRUE
J 0
(-3500 2675);
DISPLAY 0.872340 (-3500 2675);
DISPLAY INVISIBLE (-3500 2675);
FORCEPROP 1 LAST COMMENT_BODY TRUE
J 0
(-3700 2700);
DISPLAY 0.872340 (-3700 2700);
PAINT GREEN (-3700 2700);
DISPLAY INVISIBLE (-3700 2700);
FORCEPROP 2 LAST PATH I18
J 0
(-3775 2875);
DISPLAY 1.021277 (-3775 2875);
DISPLAY INVISIBLE (-3775 2875);
FORCEADD Q_RES..1
(-3850 1200);
FORCEPROP 1 LAST PART_NUMBER CS04992FB07
J 0
(-3750 1175);
DISPLAY 0.404255 (-3750 1175);
DISPLAY INVISIBLE (-3750 1175);
FORCEPROP 1 LAST VALUE 49.9
J 2
(-3625 1200);
DISPLAY 0.510638 (-3625 1200);
FORCEPROP 1 LAST MATERIAL CHIP
J 0
(-4000 1175);
DISPLAY 0.404255 (-4000 1175);
FORCEPROP 1 LAST $LOCATION R3896
J 0
(-4100 1200);
DISPLAY 0.638298 (-4100 1200);
FORCEPROP 1 LASTPIN (-3950 1200) $PN 1
J 0
(-3938 1212);
DISPLAY 0.787234 (-3938 1212);
PAINT MONO (-3938 1212);
FORCEPROP 1 LASTPIN (-3750 1200) $PN 2
J 0
(-3788 1212);
DISPLAY 0.787234 (-3788 1212);
PAINT MONO (-3788 1212);
FORCEPROP 2 LAST CDS_LIB pure_quanta
J 0
(-3850 1200);
DISPLAY INVISIBLE (-3850 1200);
FORCEPROP 1 LAST PACK_TYPE 0402LF
J 0
(-3550 1200);
DISPLAY 0.510638 (-3550 1200);
DISPLAY INVISIBLE (-3550 1200);
FORCEPROP 1 LAST TOLERANCE 1%
J 0
(-3625 1200);
DISPLAY 0.510638 (-3625 1200);
DISPLAY INVISIBLE (-3625 1200);
FORCEPROP 1 LAST WATTAGE 1/16W
J 2
(-3550 1150);
DISPLAY 0.404255 (-3550 1150);
DISPLAY INVISIBLE (-3550 1150);
FORCEPROP 1 LAST PATH I180
J 0
(-3900 1350);
DISPLAY 0.978723 (-3900 1350);
PAINT WHITE (-3900 1350);
DISPLAY INVISIBLE (-3900 1350);
FORCEPROP 0 LAST CDS_LOCATION R3896
J 0
(-4000 1250);
DISPLAY 1.021277 (-4000 1250);
DISPLAY INVISIBLE (-4000 1250);
FORCEPROP 0 LAST $SEC 1
J 0
(-4000 1250);
DISPLAY 0.680851 (-4000 1250);
PAINT MONO (-4000 1250);
DISPLAY INVISIBLE (-4000 1250);
FORCEPROP 0 LAST CDS_SEC 1
J 0
(-4000 1250);
DISPLAY 1.021277 (-4000 1250);
DISPLAY INVISIBLE (-4000 1250);
FORCEADD OFFPAGE..1
(-3825 2750);
FORCEPROP 2 LAST $XR0 53 
J 0
(-4046 2750);
DISPLAY 0.638298 (-4046 2750);
PAINT MONO (-4046 2750);
FORCEPROP 2 LAST CDS_LIB standard
J 0
(-3825 2750);
PAINT MONO (-3825 2750);
DISPLAY INVISIBLE (-3825 2750);
FORCEPROP 1 LAST OFFPAGE TRUE
J 0
(-3500 2625);
DISPLAY 0.872340 (-3500 2625);
DISPLAY INVISIBLE (-3500 2625);
FORCEPROP 1 LAST COMMENT_BODY TRUE
J 0
(-3700 2650);
DISPLAY 0.872340 (-3700 2650);
PAINT GREEN (-3700 2650);
DISPLAY INVISIBLE (-3700 2650);
FORCEPROP 2 LAST PATH I19
J 0
(-3775 2825);
DISPLAY 1.021277 (-3775 2825);
DISPLAY INVISIBLE (-3775 2825);
FORCEADD Q_RES..2
(-2675 -250);
FORCEPROP 1 LAST PART_NUMBER CS38452FB05
J 0
(-2635 -375);
DISPLAY 0.978723 (-2635 -375);
DISPLAY INVISIBLE (-2635 -375);
FORCEPROP 1 LAST VALUE 84.5K
J 0
(-2630 -175);
DISPLAY 0.978723 (-2630 -175);
FORCEPROP 1 LAST PACK_TYPE 0402LF
J 0
(-2635 -425);
DISPLAY 0.978723 (-2635 -425);
FORCEPROP 1 LAST WATTAGE 1/16W
J 0
(-2635 -275);
DISPLAY 0.978723 (-2635 -275);
FORCEPROP 1 LAST TOLERANCE 1%
J 0
(-2630 -225);
DISPLAY 0.978723 (-2630 -225);
FORCEPROP 1 LAST MATERIAL CHIP
J 0
(-2635 -325);
DISPLAY 0.978723 (-2635 -325);
FORCEPROP 1 LAST $LOCATION R47
J 0
(-2630 -125);
DISPLAY 0.978723 (-2630 -125);
FORCEPROP 1 LASTPIN (-2675 -150) $PN 1
J 0
(-2670 -188);
DISPLAY 0.787234 (-2670 -188);
FORCEPROP 1 LASTPIN (-2675 -350) $PN 2
J 0
(-2670 -340);
DISPLAY 0.787234 (-2670 -340);
FORCEPROP 2 LAST CDS_LIB pure_quanta
J 0
(-2675 -250);
PAINT MONO (-2675 -250);
DISPLAY INVISIBLE (-2675 -250);
FORCEPROP 1 LAST PATH I2
J 0
(-2625 -75);
DISPLAY 0.978723 (-2625 -75);
PAINT WHITE (-2625 -75);
DISPLAY INVISIBLE (-2625 -75);
FORCEPROP 1 LAST $LOCATION R47
J 0
(-2625 -25);
DISPLAY 1.021277 (-2625 -25);
DISPLAY INVISIBLE (-2625 -25);
FORCEPROP 2 LAST CDS_LOCATION R47
J 0
(-2625 -25);
DISPLAY 1.021277 (-2625 -25);
DISPLAY INVISIBLE (-2625 -25);
FORCEPROP 2 LAST $SEC 1
J 0
(-2625 -25);
DISPLAY 0.680851 (-2625 -25);
PAINT MONO (-2625 -25);
DISPLAY INVISIBLE (-2625 -25);
FORCEPROP 2 LAST CDS_SEC 1
J 0
(-2625 -25);
DISPLAY 1.021277 (-2625 -25);
DISPLAY INVISIBLE (-2625 -25);
FORCEADD OFFPAGE..1
(-3825 2950);
FORCEPROP 2 LAST $XR0 53 
J 0
(-4046 2950);
DISPLAY 0.638298 (-4046 2950);
PAINT MONO (-4046 2950);
FORCEPROP 2 LAST CDS_LIB standard
J 0
(-3825 2950);
PAINT MONO (-3825 2950);
DISPLAY INVISIBLE (-3825 2950);
FORCEPROP 1 LAST OFFPAGE TRUE
J 0
(-3500 2825);
DISPLAY 0.872340 (-3500 2825);
DISPLAY INVISIBLE (-3500 2825);
FORCEPROP 1 LAST COMMENT_BODY TRUE
J 0
(-3700 2850);
DISPLAY 0.872340 (-3700 2850);
PAINT GREEN (-3700 2850);
DISPLAY INVISIBLE (-3700 2850);
FORCEPROP 2 LAST PATH I20
J 0
(-3775 3025);
DISPLAY 1.021277 (-3775 3025);
DISPLAY INVISIBLE (-3775 3025);
FORCEADD OFFPAGE..1
(-3825 2900);
FORCEPROP 2 LAST $XR0 53 
J 0
(-4046 2900);
DISPLAY 0.638298 (-4046 2900);
PAINT MONO (-4046 2900);
FORCEPROP 2 LAST CDS_LIB standard
J 0
(-3825 2900);
PAINT MONO (-3825 2900);
DISPLAY INVISIBLE (-3825 2900);
FORCEPROP 1 LAST OFFPAGE TRUE
J 0
(-3500 2775);
DISPLAY 0.872340 (-3500 2775);
DISPLAY INVISIBLE (-3500 2775);
FORCEPROP 1 LAST COMMENT_BODY TRUE
J 0
(-3700 2800);
DISPLAY 0.872340 (-3700 2800);
PAINT GREEN (-3700 2800);
DISPLAY INVISIBLE (-3700 2800);
FORCEPROP 2 LAST PATH I21
J 0
(-3775 2975);
DISPLAY 1.021277 (-3775 2975);
DISPLAY INVISIBLE (-3775 2975);
FORCEADD OFFPAGE..1
(-3825 3050);
FORCEPROP 2 LAST $XR1 102 
J 0
(-4166 3050);
DISPLAY 0.638298 (-4166 3050);
PAINT MONO (-4166 3050);
FORCEPROP 2 LAST $XR0 53 
J 0
(-4046 3050);
DISPLAY 0.638298 (-4046 3050);
PAINT MONO (-4046 3050);
FORCEPROP 2 LAST CDS_LIB standard
J 0
(-3825 3050);
PAINT MONO (-3825 3050);
DISPLAY INVISIBLE (-3825 3050);
FORCEPROP 1 LAST OFFPAGE TRUE
J 0
(-3500 2925);
DISPLAY 0.872340 (-3500 2925);
DISPLAY INVISIBLE (-3500 2925);
FORCEPROP 1 LAST COMMENT_BODY TRUE
J 0
(-3700 2950);
DISPLAY 0.872340 (-3700 2950);
PAINT GREEN (-3700 2950);
DISPLAY INVISIBLE (-3700 2950);
FORCEPROP 2 LAST PATH I22
J 0
(-3775 3125);
DISPLAY 1.021277 (-3775 3125);
DISPLAY INVISIBLE (-3775 3125);
FORCEADD OFFPAGE..1
(-3825 3100);
FORCEPROP 2 LAST $XR1 102 
J 0
(-4166 3100);
DISPLAY 0.638298 (-4166 3100);
PAINT MONO (-4166 3100);
FORCEPROP 2 LAST $XR0 53 
J 0
(-4046 3100);
DISPLAY 0.638298 (-4046 3100);
PAINT MONO (-4046 3100);
FORCEPROP 2 LAST CDS_LIB standard
J 0
(-3825 3100);
PAINT MONO (-3825 3100);
DISPLAY INVISIBLE (-3825 3100);
FORCEPROP 1 LAST OFFPAGE TRUE
J 0
(-3500 2975);
DISPLAY 0.872340 (-3500 2975);
DISPLAY INVISIBLE (-3500 2975);
FORCEPROP 1 LAST COMMENT_BODY TRUE
J 0
(-3700 3000);
DISPLAY 0.872340 (-3700 3000);
PAINT GREEN (-3700 3000);
DISPLAY INVISIBLE (-3700 3000);
FORCEPROP 2 LAST PATH I23
J 0
(-3775 3175);
DISPLAY 1.021277 (-3775 3175);
DISPLAY INVISIBLE (-3775 3175);
FORCEADD OFFPAGE..1
(-3825 3525);
FORCEPROP 2 LAST $XR1 102 
J 0
(-4166 3525);
DISPLAY 0.638298 (-4166 3525);
PAINT MONO (-4166 3525);
FORCEPROP 2 LAST $XR0 53 
J 0
(-4046 3525);
DISPLAY 0.638298 (-4046 3525);
PAINT MONO (-4046 3525);
FORCEPROP 2 LAST CDS_LIB standard
J 0
(-3825 3525);
PAINT MONO (-3825 3525);
DISPLAY INVISIBLE (-3825 3525);
FORCEPROP 1 LAST OFFPAGE TRUE
J 0
(-3500 3400);
DISPLAY 0.872340 (-3500 3400);
DISPLAY INVISIBLE (-3500 3400);
FORCEPROP 1 LAST COMMENT_BODY TRUE
J 0
(-3700 3425);
DISPLAY 0.872340 (-3700 3425);
PAINT GREEN (-3700 3425);
DISPLAY INVISIBLE (-3700 3425);
FORCEPROP 2 LAST PATH I24
J 0
(-3775 3600);
DISPLAY 1.021277 (-3775 3600);
DISPLAY INVISIBLE (-3775 3600);
FORCEADD TAP..1
R 2
(-2900 1750);
FORCEPROP 3 LASTPIN (-2850 1750) SIG_NAME M_C_CPU1_SB_CB<1>
J 0
(-2840 1760);
DISPLAY 0.659574 (-2840 1760);
PAINT MONO (-2840 1760);
DISPLAY INVISIBLE (-2840 1760);
FORCEPROP 1 LASTPIN (-2850 1750) BN 1
J 2
(-2838 1758);
DISPLAY 0.680851 (-2838 1758);
PAINT GREEN (-2838 1758);
FORCEPROP 2 LAST CDS_LIB standard
J 0
(-2900 1750);
DISPLAY INVISIBLE (-2900 1750);
FORCEPROP 1 LAST BODY_TYPE PLUMBING
J 2
(-2900 1800);
DISPLAY 0.872340 (-2900 1800);
PAINT GREEN (-2900 1800);
DISPLAY INVISIBLE (-2900 1800);
FORCEPROP 1 LAST HDL_TAP TRUE
J 2
(-3225 1625);
DISPLAY 0.872340 (-3225 1625);
DISPLAY INVISIBLE (-3225 1625);
FORCEPROP 1 LAST PATH I25
J 2
(-2898 1750);
DISPLAY 0.872340 (-2898 1750);
PAINT GREEN (-2898 1750);
DISPLAY INVISIBLE (-2898 1750);
FORCEADD TAP..1
R 2
(-2900 1800);
FORCEPROP 3 LASTPIN (-2850 1800) SIG_NAME M_C_CPU1_SB_CB<2>
J 0
(-2840 1810);
DISPLAY 0.659574 (-2840 1810);
PAINT MONO (-2840 1810);
DISPLAY INVISIBLE (-2840 1810);
FORCEPROP 1 LASTPIN (-2850 1800) BN 2
J 2
(-2838 1808);
DISPLAY 0.680851 (-2838 1808);
PAINT GREEN (-2838 1808);
FORCEPROP 2 LAST CDS_LIB standard
J 0
(-2900 1800);
DISPLAY INVISIBLE (-2900 1800);
FORCEPROP 1 LAST BODY_TYPE PLUMBING
J 2
(-2900 1850);
DISPLAY 0.872340 (-2900 1850);
PAINT GREEN (-2900 1850);
DISPLAY INVISIBLE (-2900 1850);
FORCEPROP 1 LAST HDL_TAP TRUE
J 2
(-3225 1675);
DISPLAY 0.872340 (-3225 1675);
DISPLAY INVISIBLE (-3225 1675);
FORCEPROP 1 LAST PATH I26
J 2
(-2898 1800);
DISPLAY 0.872340 (-2898 1800);
PAINT GREEN (-2898 1800);
DISPLAY INVISIBLE (-2898 1800);
FORCEADD TAP..1
R 2
(-2900 1850);
FORCEPROP 3 LASTPIN (-2850 1850) SIG_NAME M_C_CPU1_SB_CB<3>
J 0
(-2840 1860);
DISPLAY 0.659574 (-2840 1860);
PAINT MONO (-2840 1860);
DISPLAY INVISIBLE (-2840 1860);
FORCEPROP 1 LASTPIN (-2850 1850) BN 3
J 2
(-2838 1858);
DISPLAY 0.680851 (-2838 1858);
PAINT GREEN (-2838 1858);
FORCEPROP 2 LAST CDS_LIB standard
J 0
(-2900 1850);
DISPLAY INVISIBLE (-2900 1850);
FORCEPROP 1 LAST BODY_TYPE PLUMBING
J 2
(-2900 1900);
DISPLAY 0.872340 (-2900 1900);
PAINT GREEN (-2900 1900);
DISPLAY INVISIBLE (-2900 1900);
FORCEPROP 1 LAST HDL_TAP TRUE
J 2
(-3225 1725);
DISPLAY 0.872340 (-3225 1725);
DISPLAY INVISIBLE (-3225 1725);
FORCEPROP 1 LAST PATH I27
J 2
(-2898 1850);
DISPLAY 0.872340 (-2898 1850);
PAINT GREEN (-2898 1850);
DISPLAY INVISIBLE (-2898 1850);
FORCEADD TAP..1
R 2
(-2900 1900);
FORCEPROP 3 LASTPIN (-2850 1900) SIG_NAME M_C_CPU1_SB_CB<4>
J 0
(-2840 1910);
DISPLAY 0.659574 (-2840 1910);
PAINT MONO (-2840 1910);
DISPLAY INVISIBLE (-2840 1910);
FORCEPROP 1 LASTPIN (-2850 1900) BN 4
J 2
(-2838 1908);
DISPLAY 0.680851 (-2838 1908);
PAINT GREEN (-2838 1908);
FORCEPROP 2 LAST CDS_LIB standard
J 0
(-2900 1900);
DISPLAY INVISIBLE (-2900 1900);
FORCEPROP 1 LAST BODY_TYPE PLUMBING
J 2
(-2900 1950);
DISPLAY 0.872340 (-2900 1950);
PAINT GREEN (-2900 1950);
DISPLAY INVISIBLE (-2900 1950);
FORCEPROP 1 LAST HDL_TAP TRUE
J 2
(-3225 1775);
DISPLAY 0.872340 (-3225 1775);
DISPLAY INVISIBLE (-3225 1775);
FORCEPROP 1 LAST PATH I28
J 2
(-2898 1900);
DISPLAY 0.872340 (-2898 1900);
PAINT GREEN (-2898 1900);
DISPLAY INVISIBLE (-2898 1900);
FORCEADD TAP..1
R 2
(-2900 1950);
FORCEPROP 3 LASTPIN (-2850 1950) SIG_NAME M_C_CPU1_SB_CB<5>
J 0
(-2840 1960);
DISPLAY 0.659574 (-2840 1960);
PAINT MONO (-2840 1960);
DISPLAY INVISIBLE (-2840 1960);
FORCEPROP 1 LASTPIN (-2850 1950) BN 5
J 2
(-2838 1958);
DISPLAY 0.680851 (-2838 1958);
PAINT GREEN (-2838 1958);
FORCEPROP 2 LAST CDS_LIB standard
J 0
(-2900 1950);
DISPLAY INVISIBLE (-2900 1950);
FORCEPROP 1 LAST BODY_TYPE PLUMBING
J 2
(-2900 2000);
DISPLAY 0.872340 (-2900 2000);
PAINT GREEN (-2900 2000);
DISPLAY INVISIBLE (-2900 2000);
FORCEPROP 1 LAST HDL_TAP TRUE
J 2
(-3225 1825);
DISPLAY 0.872340 (-3225 1825);
DISPLAY INVISIBLE (-3225 1825);
FORCEPROP 1 LAST PATH I29
J 2
(-2898 1950);
DISPLAY 0.872340 (-2898 1950);
PAINT GREEN (-2898 1950);
DISPLAY INVISIBLE (-2898 1950);
FORCEADD OFFPAGE..2
R 2
(-3825 -50);
FORCEPROP 2 LAST $XR0 103 
J 0
(-4080 -50);
DISPLAY 0.638298 (-4080 -50);
PAINT MONO (-4080 -50);
FORCEPROP 2 LAST CDS_LIB standard
J 0
(-3825 -50);
PAINT MONO (-3825 -50);
DISPLAY INVISIBLE (-3825 -50);
FORCEPROP 1 LAST OFFPAGE TRUE
J 2
(-4150 -175);
DISPLAY 0.872340 (-4150 -175);
DISPLAY INVISIBLE (-4150 -175);
FORCEPROP 1 LAST COMMENT_BODY TRUE
J 2
(-3780 -145);
DISPLAY 0.872340 (-3780 -145);
PAINT GREEN (-3780 -145);
DISPLAY INVISIBLE (-3780 -145);
FORCEPROP 2 LAST PATH I3
J 0
(-3775 25);
DISPLAY 1.021277 (-3775 25);
DISPLAY INVISIBLE (-3775 25);
FORCEADD TAP..1
R 2
(-2900 2000);
FORCEPROP 3 LASTPIN (-2850 2000) SIG_NAME M_C_CPU1_SB_CB<6>
J 0
(-2840 2010);
DISPLAY 0.659574 (-2840 2010);
PAINT MONO (-2840 2010);
DISPLAY INVISIBLE (-2840 2010);
FORCEPROP 1 LASTPIN (-2850 2000) BN 6
J 2
(-2838 2008);
DISPLAY 0.680851 (-2838 2008);
PAINT GREEN (-2838 2008);
FORCEPROP 2 LAST CDS_LIB standard
J 0
(-2900 2000);
DISPLAY INVISIBLE (-2900 2000);
FORCEPROP 1 LAST BODY_TYPE PLUMBING
J 2
(-2900 2050);
DISPLAY 0.872340 (-2900 2050);
PAINT GREEN (-2900 2050);
DISPLAY INVISIBLE (-2900 2050);
FORCEPROP 1 LAST HDL_TAP TRUE
J 2
(-3225 1875);
DISPLAY 0.872340 (-3225 1875);
DISPLAY INVISIBLE (-3225 1875);
FORCEPROP 1 LAST PATH I30
J 2
(-2898 2000);
DISPLAY 0.872340 (-2898 2000);
PAINT GREEN (-2898 2000);
DISPLAY INVISIBLE (-2898 2000);
FORCEADD TAP..1
R 2
(-2900 2050);
FORCEPROP 3 LASTPIN (-2850 2050) SIG_NAME M_C_CPU1_SB_CB<7>
J 0
(-2840 2060);
DISPLAY 0.659574 (-2840 2060);
PAINT MONO (-2840 2060);
DISPLAY INVISIBLE (-2840 2060);
FORCEPROP 1 LASTPIN (-2850 2050) BN 7
J 2
(-2838 2058);
DISPLAY 0.680851 (-2838 2058);
PAINT GREEN (-2838 2058);
FORCEPROP 2 LAST CDS_LIB standard
J 0
(-2900 2050);
DISPLAY INVISIBLE (-2900 2050);
FORCEPROP 1 LAST BODY_TYPE PLUMBING
J 2
(-2900 2100);
DISPLAY 0.872340 (-2900 2100);
PAINT GREEN (-2900 2100);
DISPLAY INVISIBLE (-2900 2100);
FORCEPROP 1 LAST HDL_TAP TRUE
J 2
(-3225 1925);
DISPLAY 0.872340 (-3225 1925);
DISPLAY INVISIBLE (-3225 1925);
FORCEPROP 1 LAST PATH I31
J 2
(-2898 2050);
DISPLAY 0.872340 (-2898 2050);
PAINT GREEN (-2898 2050);
DISPLAY INVISIBLE (-2898 2050);
FORCEADD TAP..1
R 2
(-2900 2150);
FORCEPROP 3 LASTPIN (-2850 2150) SIG_NAME M_C_CPU1_SA_CB<0>
J 0
(-2840 2160);
DISPLAY 0.659574 (-2840 2160);
PAINT MONO (-2840 2160);
DISPLAY INVISIBLE (-2840 2160);
FORCEPROP 1 LASTPIN (-2850 2150) BN 0
J 2
(-2838 2158);
DISPLAY 0.680851 (-2838 2158);
PAINT GREEN (-2838 2158);
FORCEPROP 2 LAST CDS_LIB standard
J 0
(-2900 2150);
PAINT MONO (-2900 2150);
DISPLAY INVISIBLE (-2900 2150);
FORCEPROP 1 LAST BODY_TYPE PLUMBING
J 2
(-2900 2200);
DISPLAY 0.872340 (-2900 2200);
PAINT GREEN (-2900 2200);
DISPLAY INVISIBLE (-2900 2200);
FORCEPROP 1 LAST HDL_TAP TRUE
J 2
(-3225 2025);
DISPLAY 0.872340 (-3225 2025);
DISPLAY INVISIBLE (-3225 2025);
FORCEPROP 1 LAST PATH I32
J 2
(-2898 2150);
DISPLAY 0.872340 (-2898 2150);
PAINT GREEN (-2898 2150);
DISPLAY INVISIBLE (-2898 2150);
FORCEADD TAP..1
R 2
(-2900 2200);
FORCEPROP 3 LASTPIN (-2850 2200) SIG_NAME M_C_CPU1_SA_CB<1>
J 0
(-2840 2210);
DISPLAY 0.659574 (-2840 2210);
PAINT MONO (-2840 2210);
DISPLAY INVISIBLE (-2840 2210);
FORCEPROP 1 LASTPIN (-2850 2200) BN 1
J 2
(-2838 2208);
DISPLAY 0.680851 (-2838 2208);
PAINT GREEN (-2838 2208);
FORCEPROP 2 LAST CDS_LIB standard
J 0
(-2900 2200);
DISPLAY INVISIBLE (-2900 2200);
FORCEPROP 1 LAST BODY_TYPE PLUMBING
J 2
(-2900 2250);
DISPLAY 0.872340 (-2900 2250);
PAINT GREEN (-2900 2250);
DISPLAY INVISIBLE (-2900 2250);
FORCEPROP 1 LAST HDL_TAP TRUE
J 2
(-3225 2075);
DISPLAY 0.872340 (-3225 2075);
DISPLAY INVISIBLE (-3225 2075);
FORCEPROP 1 LAST PATH I33
J 2
(-2898 2200);
DISPLAY 0.872340 (-2898 2200);
PAINT GREEN (-2898 2200);
DISPLAY INVISIBLE (-2898 2200);
FORCEADD TAP..1
R 2
(-2900 2250);
FORCEPROP 3 LASTPIN (-2850 2250) SIG_NAME M_C_CPU1_SA_CB<2>
J 0
(-2840 2260);
DISPLAY 0.659574 (-2840 2260);
PAINT MONO (-2840 2260);
DISPLAY INVISIBLE (-2840 2260);
FORCEPROP 1 LASTPIN (-2850 2250) BN 2
J 2
(-2838 2258);
DISPLAY 0.680851 (-2838 2258);
PAINT GREEN (-2838 2258);
FORCEPROP 2 LAST CDS_LIB standard
J 0
(-2900 2250);
DISPLAY INVISIBLE (-2900 2250);
FORCEPROP 1 LAST BODY_TYPE PLUMBING
J 2
(-2900 2300);
DISPLAY 0.872340 (-2900 2300);
PAINT GREEN (-2900 2300);
DISPLAY INVISIBLE (-2900 2300);
FORCEPROP 1 LAST HDL_TAP TRUE
J 2
(-3225 2125);
DISPLAY 0.872340 (-3225 2125);
DISPLAY INVISIBLE (-3225 2125);
FORCEPROP 1 LAST PATH I34
J 2
(-2898 2250);
DISPLAY 0.872340 (-2898 2250);
PAINT GREEN (-2898 2250);
DISPLAY INVISIBLE (-2898 2250);
FORCEADD TAP..1
R 2
(-2900 2300);
FORCEPROP 3 LASTPIN (-2850 2300) SIG_NAME M_C_CPU1_SA_CB<3>
J 0
(-2840 2310);
DISPLAY 0.659574 (-2840 2310);
PAINT MONO (-2840 2310);
DISPLAY INVISIBLE (-2840 2310);
FORCEPROP 1 LASTPIN (-2850 2300) BN 3
J 2
(-2838 2308);
DISPLAY 0.680851 (-2838 2308);
PAINT GREEN (-2838 2308);
FORCEPROP 2 LAST CDS_LIB standard
J 0
(-2900 2300);
DISPLAY INVISIBLE (-2900 2300);
FORCEPROP 1 LAST BODY_TYPE PLUMBING
J 2
(-2900 2350);
DISPLAY 0.872340 (-2900 2350);
PAINT GREEN (-2900 2350);
DISPLAY INVISIBLE (-2900 2350);
FORCEPROP 1 LAST HDL_TAP TRUE
J 2
(-3225 2175);
DISPLAY 0.872340 (-3225 2175);
DISPLAY INVISIBLE (-3225 2175);
FORCEPROP 1 LAST PATH I35
J 2
(-2898 2300);
DISPLAY 0.872340 (-2898 2300);
PAINT GREEN (-2898 2300);
DISPLAY INVISIBLE (-2898 2300);
FORCEADD TAP..1
R 2
(-2900 2350);
FORCEPROP 3 LASTPIN (-2850 2350) SIG_NAME M_C_CPU1_SA_CB<4>
J 0
(-2840 2360);
DISPLAY 0.659574 (-2840 2360);
PAINT MONO (-2840 2360);
DISPLAY INVISIBLE (-2840 2360);
FORCEPROP 1 LASTPIN (-2850 2350) BN 4
J 2
(-2838 2358);
DISPLAY 0.680851 (-2838 2358);
PAINT GREEN (-2838 2358);
FORCEPROP 2 LAST CDS_LIB standard
J 0
(-2900 2350);
DISPLAY INVISIBLE (-2900 2350);
FORCEPROP 1 LAST BODY_TYPE PLUMBING
J 2
(-2900 2400);
DISPLAY 0.872340 (-2900 2400);
PAINT GREEN (-2900 2400);
DISPLAY INVISIBLE (-2900 2400);
FORCEPROP 1 LAST HDL_TAP TRUE
J 2
(-3225 2225);
DISPLAY 0.872340 (-3225 2225);
DISPLAY INVISIBLE (-3225 2225);
FORCEPROP 1 LAST PATH I36
J 2
(-2898 2350);
DISPLAY 0.872340 (-2898 2350);
PAINT GREEN (-2898 2350);
DISPLAY INVISIBLE (-2898 2350);
FORCEADD TAP..1
R 2
(-2900 2400);
FORCEPROP 3 LASTPIN (-2850 2400) SIG_NAME M_C_CPU1_SA_CB<5>
J 0
(-2840 2410);
DISPLAY 0.659574 (-2840 2410);
PAINT MONO (-2840 2410);
DISPLAY INVISIBLE (-2840 2410);
FORCEPROP 1 LASTPIN (-2850 2400) BN 5
J 2
(-2838 2408);
DISPLAY 0.680851 (-2838 2408);
PAINT GREEN (-2838 2408);
FORCEPROP 2 LAST CDS_LIB standard
J 0
(-2900 2400);
DISPLAY INVISIBLE (-2900 2400);
FORCEPROP 1 LAST BODY_TYPE PLUMBING
J 2
(-2900 2450);
DISPLAY 0.872340 (-2900 2450);
PAINT GREEN (-2900 2450);
DISPLAY INVISIBLE (-2900 2450);
FORCEPROP 1 LAST HDL_TAP TRUE
J 2
(-3225 2275);
DISPLAY 0.872340 (-3225 2275);
DISPLAY INVISIBLE (-3225 2275);
FORCEPROP 1 LAST PATH I37
J 2
(-2898 2400);
DISPLAY 0.872340 (-2898 2400);
PAINT GREEN (-2898 2400);
DISPLAY INVISIBLE (-2898 2400);
FORCEADD TAP..1
R 2
(-2900 2450);
FORCEPROP 3 LASTPIN (-2850 2450) SIG_NAME M_C_CPU1_SA_CB<6>
J 0
(-2840 2460);
DISPLAY 0.659574 (-2840 2460);
PAINT MONO (-2840 2460);
DISPLAY INVISIBLE (-2840 2460);
FORCEPROP 1 LASTPIN (-2850 2450) BN 6
J 2
(-2838 2458);
DISPLAY 0.680851 (-2838 2458);
PAINT GREEN (-2838 2458);
FORCEPROP 2 LAST CDS_LIB standard
J 0
(-2900 2450);
DISPLAY INVISIBLE (-2900 2450);
FORCEPROP 1 LAST BODY_TYPE PLUMBING
J 2
(-2900 2500);
DISPLAY 0.872340 (-2900 2500);
PAINT GREEN (-2900 2500);
DISPLAY INVISIBLE (-2900 2500);
FORCEPROP 1 LAST HDL_TAP TRUE
J 2
(-3225 2325);
DISPLAY 0.872340 (-3225 2325);
DISPLAY INVISIBLE (-3225 2325);
FORCEPROP 1 LAST PATH I38
J 2
(-2898 2450);
DISPLAY 0.872340 (-2898 2450);
PAINT GREEN (-2898 2450);
DISPLAY INVISIBLE (-2898 2450);
FORCEADD TAP..1
R 2
(-2900 2500);
FORCEPROP 3 LASTPIN (-2850 2500) SIG_NAME M_C_CPU1_SA_CB<7>
J 0
(-2840 2510);
DISPLAY 0.659574 (-2840 2510);
PAINT MONO (-2840 2510);
DISPLAY INVISIBLE (-2840 2510);
FORCEPROP 1 LASTPIN (-2850 2500) BN 7
J 2
(-2838 2508);
DISPLAY 0.680851 (-2838 2508);
PAINT GREEN (-2838 2508);
FORCEPROP 2 LAST CDS_LIB standard
J 0
(-2900 2500);
DISPLAY INVISIBLE (-2900 2500);
FORCEPROP 1 LAST BODY_TYPE PLUMBING
J 2
(-2900 2550);
DISPLAY 0.872340 (-2900 2550);
PAINT GREEN (-2900 2550);
DISPLAY INVISIBLE (-2900 2550);
FORCEPROP 1 LAST HDL_TAP TRUE
J 2
(-3225 2375);
DISPLAY 0.872340 (-3225 2375);
DISPLAY INVISIBLE (-3225 2375);
FORCEPROP 1 LAST PATH I39
J 2
(-2898 2500);
DISPLAY 0.872340 (-2898 2500);
PAINT GREEN (-2898 2500);
DISPLAY INVISIBLE (-2898 2500);
FORCEADD OFFPAGE..2
R 2
(-3825 450);
FORCEPROP 2 LAST $XR0 53 
J 0
(-4049 450);
DISPLAY 0.638298 (-4049 450);
PAINT MONO (-4049 450);
FORCEPROP 2 LAST CDS_LIB standard
J 0
(-3825 450);
PAINT MONO (-3825 450);
DISPLAY INVISIBLE (-3825 450);
FORCEPROP 1 LAST OFFPAGE TRUE
J 2
(-4150 325);
DISPLAY 0.872340 (-4150 325);
DISPLAY INVISIBLE (-4150 325);
FORCEPROP 1 LAST COMMENT_BODY TRUE
J 2
(-3780 355);
DISPLAY 0.872340 (-3780 355);
PAINT GREEN (-3780 355);
DISPLAY INVISIBLE (-3780 355);
FORCEPROP 2 LAST PATH I4
J 0
(-3775 525);
DISPLAY 1.021277 (-3775 525);
DISPLAY INVISIBLE (-3775 525);
FORCEADD TAP..1
R 2
(-2900 3200);
FORCEPROP 3 LASTPIN (-2850 3200) SIG_NAME M_C_CPU1_SB_CA<0>
J 0
(-2840 3210);
DISPLAY 0.659574 (-2840 3210);
PAINT MONO (-2840 3210);
DISPLAY INVISIBLE (-2840 3210);
FORCEPROP 1 LASTPIN (-2850 3200) BN 0
J 2
(-2838 3208);
DISPLAY 0.680851 (-2838 3208);
PAINT GREEN (-2838 3208);
FORCEPROP 2 LAST CDS_LIB standard
J 0
(-2900 3200);
DISPLAY INVISIBLE (-2900 3200);
FORCEPROP 1 LAST BODY_TYPE PLUMBING
J 2
(-2900 3250);
DISPLAY 0.872340 (-2900 3250);
PAINT GREEN (-2900 3250);
DISPLAY INVISIBLE (-2900 3250);
FORCEPROP 1 LAST HDL_TAP TRUE
J 2
(-3225 3075);
DISPLAY 0.872340 (-3225 3075);
DISPLAY INVISIBLE (-3225 3075);
FORCEPROP 1 LAST PATH I40
J 2
(-2898 3200);
DISPLAY 0.872340 (-2898 3200);
PAINT GREEN (-2898 3200);
DISPLAY INVISIBLE (-2898 3200);
FORCEADD TAP..1
R 2
(-2900 3250);
FORCEPROP 3 LASTPIN (-2850 3250) SIG_NAME M_C_CPU1_SB_CA<1>
J 0
(-2840 3260);
DISPLAY 0.659574 (-2840 3260);
PAINT MONO (-2840 3260);
DISPLAY INVISIBLE (-2840 3260);
FORCEPROP 1 LASTPIN (-2850 3250) BN 1
J 2
(-2838 3258);
DISPLAY 0.680851 (-2838 3258);
PAINT GREEN (-2838 3258);
FORCEPROP 2 LAST CDS_LIB standard
J 0
(-2900 3250);
DISPLAY INVISIBLE (-2900 3250);
FORCEPROP 1 LAST BODY_TYPE PLUMBING
J 2
(-2900 3300);
DISPLAY 0.872340 (-2900 3300);
PAINT GREEN (-2900 3300);
DISPLAY INVISIBLE (-2900 3300);
FORCEPROP 1 LAST HDL_TAP TRUE
J 2
(-3225 3125);
DISPLAY 0.872340 (-3225 3125);
DISPLAY INVISIBLE (-3225 3125);
FORCEPROP 1 LAST PATH I41
J 2
(-2898 3250);
DISPLAY 0.872340 (-2898 3250);
PAINT GREEN (-2898 3250);
DISPLAY INVISIBLE (-2898 3250);
FORCEADD TAP..1
R 2
(-2900 3300);
FORCEPROP 3 LASTPIN (-2850 3300) SIG_NAME M_C_CPU1_SB_CA<2>
J 0
(-2840 3310);
DISPLAY 0.659574 (-2840 3310);
PAINT MONO (-2840 3310);
DISPLAY INVISIBLE (-2840 3310);
FORCEPROP 1 LASTPIN (-2850 3300) BN 2
J 2
(-2838 3308);
DISPLAY 0.680851 (-2838 3308);
PAINT GREEN (-2838 3308);
FORCEPROP 2 LAST CDS_LIB standard
J 0
(-2900 3300);
DISPLAY INVISIBLE (-2900 3300);
FORCEPROP 1 LAST BODY_TYPE PLUMBING
J 2
(-2900 3350);
DISPLAY 0.872340 (-2900 3350);
PAINT GREEN (-2900 3350);
DISPLAY INVISIBLE (-2900 3350);
FORCEPROP 1 LAST HDL_TAP TRUE
J 2
(-3225 3175);
DISPLAY 0.872340 (-3225 3175);
DISPLAY INVISIBLE (-3225 3175);
FORCEPROP 1 LAST PATH I42
J 2
(-2898 3300);
DISPLAY 0.872340 (-2898 3300);
PAINT GREEN (-2898 3300);
DISPLAY INVISIBLE (-2898 3300);
FORCEADD TAP..1
R 2
(-2900 3350);
FORCEPROP 3 LASTPIN (-2850 3350) SIG_NAME M_C_CPU1_SB_CA<3>
J 0
(-2840 3360);
DISPLAY 0.659574 (-2840 3360);
PAINT MONO (-2840 3360);
DISPLAY INVISIBLE (-2840 3360);
FORCEPROP 1 LASTPIN (-2850 3350) BN 3
J 2
(-2838 3358);
DISPLAY 0.680851 (-2838 3358);
PAINT GREEN (-2838 3358);
FORCEPROP 2 LAST CDS_LIB standard
J 0
(-2900 3350);
DISPLAY INVISIBLE (-2900 3350);
FORCEPROP 1 LAST BODY_TYPE PLUMBING
J 2
(-2900 3400);
DISPLAY 0.872340 (-2900 3400);
PAINT GREEN (-2900 3400);
DISPLAY INVISIBLE (-2900 3400);
FORCEPROP 1 LAST HDL_TAP TRUE
J 2
(-3225 3225);
DISPLAY 0.872340 (-3225 3225);
DISPLAY INVISIBLE (-3225 3225);
FORCEPROP 1 LAST PATH I43
J 2
(-2898 3350);
DISPLAY 0.872340 (-2898 3350);
PAINT GREEN (-2898 3350);
DISPLAY INVISIBLE (-2898 3350);
FORCEADD TAP..1
R 2
(-2900 3400);
FORCEPROP 3 LASTPIN (-2850 3400) SIG_NAME M_C_CPU1_SB_CA<4>
J 0
(-2840 3410);
DISPLAY 0.659574 (-2840 3410);
PAINT MONO (-2840 3410);
DISPLAY INVISIBLE (-2840 3410);
FORCEPROP 1 LASTPIN (-2850 3400) BN 4
J 2
(-2838 3408);
DISPLAY 0.680851 (-2838 3408);
PAINT GREEN (-2838 3408);
FORCEPROP 2 LAST CDS_LIB standard
J 0
(-2900 3400);
DISPLAY INVISIBLE (-2900 3400);
FORCEPROP 1 LAST BODY_TYPE PLUMBING
J 2
(-2900 3450);
DISPLAY 0.872340 (-2900 3450);
PAINT GREEN (-2900 3450);
DISPLAY INVISIBLE (-2900 3450);
FORCEPROP 1 LAST HDL_TAP TRUE
J 2
(-3225 3275);
DISPLAY 0.872340 (-3225 3275);
DISPLAY INVISIBLE (-3225 3275);
FORCEPROP 1 LAST PATH I44
J 2
(-2898 3400);
DISPLAY 0.872340 (-2898 3400);
PAINT GREEN (-2898 3400);
DISPLAY INVISIBLE (-2898 3400);
FORCEADD TAP..1
R 2
(-2900 3500);
FORCEPROP 3 LASTPIN (-2850 3500) SIG_NAME M_C_CPU1_SB_CA<6>
J 0
(-2840 3510);
DISPLAY 0.659574 (-2840 3510);
PAINT MONO (-2840 3510);
DISPLAY INVISIBLE (-2840 3510);
FORCEPROP 1 LASTPIN (-2850 3500) BN 6
J 2
(-2838 3508);
DISPLAY 0.680851 (-2838 3508);
PAINT GREEN (-2838 3508);
FORCEPROP 2 LAST CDS_LIB standard
J 0
(-2900 3500);
DISPLAY INVISIBLE (-2900 3500);
FORCEPROP 1 LAST BODY_TYPE PLUMBING
J 2
(-2900 3550);
DISPLAY 0.872340 (-2900 3550);
PAINT GREEN (-2900 3550);
DISPLAY INVISIBLE (-2900 3550);
FORCEPROP 1 LAST HDL_TAP TRUE
J 2
(-3225 3375);
DISPLAY 0.872340 (-3225 3375);
DISPLAY INVISIBLE (-3225 3375);
FORCEPROP 1 LAST PATH I45
J 2
(-2898 3500);
DISPLAY 0.872340 (-2898 3500);
PAINT GREEN (-2898 3500);
DISPLAY INVISIBLE (-2898 3500);
FORCEADD TAP..1
R 2
(-2900 3450);
FORCEPROP 3 LASTPIN (-2850 3450) SIG_NAME M_C_CPU1_SB_CA<5>
J 0
(-2840 3460);
DISPLAY 0.659574 (-2840 3460);
PAINT MONO (-2840 3460);
DISPLAY INVISIBLE (-2840 3460);
FORCEPROP 1 LASTPIN (-2850 3450) BN 5
J 2
(-2838 3458);
DISPLAY 0.680851 (-2838 3458);
PAINT GREEN (-2838 3458);
FORCEPROP 2 LAST CDS_LIB standard
J 0
(-2900 3450);
DISPLAY INVISIBLE (-2900 3450);
FORCEPROP 1 LAST BODY_TYPE PLUMBING
J 2
(-2900 3500);
DISPLAY 0.872340 (-2900 3500);
PAINT GREEN (-2900 3500);
DISPLAY INVISIBLE (-2900 3500);
FORCEPROP 1 LAST HDL_TAP TRUE
J 2
(-3225 3325);
DISPLAY 0.872340 (-3225 3325);
DISPLAY INVISIBLE (-3225 3325);
FORCEPROP 1 LAST PATH I46
J 2
(-2898 3450);
DISPLAY 0.872340 (-2898 3450);
PAINT GREEN (-2898 3450);
DISPLAY INVISIBLE (-2898 3450);
FORCEADD TAP..1
R 2
(-2900 3600);
FORCEPROP 3 LASTPIN (-2850 3600) SIG_NAME M_C_CPU1_SA_CA<0>
J 0
(-2840 3610);
DISPLAY 0.659574 (-2840 3610);
PAINT MONO (-2840 3610);
DISPLAY INVISIBLE (-2840 3610);
FORCEPROP 1 LASTPIN (-2850 3600) BN 0
J 2
(-2838 3608);
DISPLAY 0.680851 (-2838 3608);
PAINT GREEN (-2838 3608);
FORCEPROP 2 LAST CDS_LIB standard
J 0
(-2900 3600);
DISPLAY INVISIBLE (-2900 3600);
FORCEPROP 1 LAST BODY_TYPE PLUMBING
J 2
(-2900 3650);
DISPLAY 0.872340 (-2900 3650);
PAINT GREEN (-2900 3650);
DISPLAY INVISIBLE (-2900 3650);
FORCEPROP 1 LAST HDL_TAP TRUE
J 2
(-3225 3475);
DISPLAY 0.872340 (-3225 3475);
DISPLAY INVISIBLE (-3225 3475);
FORCEPROP 1 LAST PATH I47
J 2
(-2898 3600);
DISPLAY 0.872340 (-2898 3600);
PAINT GREEN (-2898 3600);
DISPLAY INVISIBLE (-2898 3600);
FORCEADD TAP..1
R 2
(-2900 3650);
FORCEPROP 3 LASTPIN (-2850 3650) SIG_NAME M_C_CPU1_SA_CA<1>
J 0
(-2840 3660);
DISPLAY 0.659574 (-2840 3660);
PAINT MONO (-2840 3660);
DISPLAY INVISIBLE (-2840 3660);
FORCEPROP 1 LASTPIN (-2850 3650) BN 1
J 2
(-2838 3658);
DISPLAY 0.680851 (-2838 3658);
PAINT GREEN (-2838 3658);
FORCEPROP 2 LAST CDS_LIB standard
J 0
(-2900 3650);
DISPLAY INVISIBLE (-2900 3650);
FORCEPROP 1 LAST BODY_TYPE PLUMBING
J 2
(-2900 3700);
DISPLAY 0.872340 (-2900 3700);
PAINT GREEN (-2900 3700);
DISPLAY INVISIBLE (-2900 3700);
FORCEPROP 1 LAST HDL_TAP TRUE
J 2
(-3225 3525);
DISPLAY 0.872340 (-3225 3525);
DISPLAY INVISIBLE (-3225 3525);
FORCEPROP 1 LAST PATH I48
J 2
(-2898 3650);
DISPLAY 0.872340 (-2898 3650);
PAINT GREEN (-2898 3650);
DISPLAY INVISIBLE (-2898 3650);
FORCEADD TAP..1
R 2
(-2900 3750);
FORCEPROP 3 LASTPIN (-2850 3750) SIG_NAME M_C_CPU1_SA_CA<3>
J 0
(-2840 3760);
DISPLAY 0.659574 (-2840 3760);
PAINT MONO (-2840 3760);
DISPLAY INVISIBLE (-2840 3760);
FORCEPROP 1 LASTPIN (-2850 3750) BN 3
J 2
(-2838 3758);
DISPLAY 0.680851 (-2838 3758);
PAINT GREEN (-2838 3758);
FORCEPROP 2 LAST CDS_LIB standard
J 0
(-2900 3750);
DISPLAY INVISIBLE (-2900 3750);
FORCEPROP 1 LAST BODY_TYPE PLUMBING
J 2
(-2900 3800);
DISPLAY 0.872340 (-2900 3800);
PAINT GREEN (-2900 3800);
DISPLAY INVISIBLE (-2900 3800);
FORCEPROP 1 LAST HDL_TAP TRUE
J 2
(-3225 3625);
DISPLAY 0.872340 (-3225 3625);
DISPLAY INVISIBLE (-3225 3625);
FORCEPROP 1 LAST PATH I49
J 2
(-2898 3750);
DISPLAY 0.872340 (-2898 3750);
PAINT GREEN (-2898 3750);
DISPLAY INVISIBLE (-2898 3750);
FORCEADD OFFPAGE..2
R 2
(-3825 500);
FORCEPROP 2 LAST $XR0 53 
J 0
(-4049 500);
DISPLAY 0.638298 (-4049 500);
PAINT MONO (-4049 500);
FORCEPROP 2 LAST CDS_LIB standard
J 0
(-3825 500);
PAINT MONO (-3825 500);
DISPLAY INVISIBLE (-3825 500);
FORCEPROP 1 LAST OFFPAGE TRUE
J 2
(-4150 375);
DISPLAY 0.872340 (-4150 375);
DISPLAY INVISIBLE (-4150 375);
FORCEPROP 1 LAST COMMENT_BODY TRUE
J 2
(-3780 405);
DISPLAY 0.872340 (-3780 405);
PAINT GREEN (-3780 405);
DISPLAY INVISIBLE (-3780 405);
FORCEPROP 2 LAST PATH I5
J 0
(-3775 575);
DISPLAY 1.021277 (-3775 575);
DISPLAY INVISIBLE (-3775 575);
FORCEADD TAP..1
R 2
(-2900 3700);
FORCEPROP 3 LASTPIN (-2850 3700) SIG_NAME M_C_CPU1_SA_CA<2>
J 0
(-2840 3710);
DISPLAY 0.659574 (-2840 3710);
PAINT MONO (-2840 3710);
DISPLAY INVISIBLE (-2840 3710);
FORCEPROP 1 LASTPIN (-2850 3700) BN 2
J 2
(-2838 3708);
DISPLAY 0.680851 (-2838 3708);
PAINT GREEN (-2838 3708);
FORCEPROP 2 LAST CDS_LIB standard
J 0
(-2900 3700);
DISPLAY INVISIBLE (-2900 3700);
FORCEPROP 1 LAST BODY_TYPE PLUMBING
J 2
(-2900 3750);
DISPLAY 0.872340 (-2900 3750);
PAINT GREEN (-2900 3750);
DISPLAY INVISIBLE (-2900 3750);
FORCEPROP 1 LAST HDL_TAP TRUE
J 2
(-3225 3575);
DISPLAY 0.872340 (-3225 3575);
DISPLAY INVISIBLE (-3225 3575);
FORCEPROP 1 LAST PATH I50
J 2
(-2898 3700);
DISPLAY 0.872340 (-2898 3700);
PAINT GREEN (-2898 3700);
DISPLAY INVISIBLE (-2898 3700);
FORCEADD SCONN288_ADR50017P087CC..1
(-2075 2175);
FORCEPROP 1 LAST PART_NUMBER DFHST8FS460
J 0
(-2520 4185);
DISPLAY 0.723404 (-2520 4185);
PAINT GREEN (-2520 4185);
DISPLAY INVISIBLE (-2520 4185);
FORCEPROP 1 LAST MATERIAL IO
J 0
(-2520 4058);
DISPLAY 0.723404 (-2520 4058);
PAINT GREEN (-2520 4058);
FORCEPROP 2 LAST VALUE SCONN288_ADR50017-P087CC
J 0
(-2525 4300);
DISPLAY 1.021277 (-2525 4300);
FORCEPROP 2 LAST PART_TYPE SMLF
J 0
(-2525 4350);
DISPLAY 1.021277 (-2525 4350);
FORCEPROP 1 LAST $LOCATION J22
J 0
(-2525 4250);
DISPLAY 0.723404 (-2525 4250);
PAINT GREEN (-2525 4250);
FORCEPROP 0 LASTPIN (-2675 1550) $PN 62
J 2
(-2685 1560);
DISPLAY 0.680851 (-2685 1560);
PAINT MONO (-2685 1560);
FORCEPROP 0 LASTPIN (-2675 3600) $PN 66
J 2
(-2685 3610);
DISPLAY 0.680851 (-2685 3610);
PAINT MONO (-2685 3610);
FORCEPROP 0 LASTPIN (-2675 3200) $PN 76
J 2
(-2685 3210);
DISPLAY 0.680851 (-2685 3210);
PAINT MONO (-2685 3210);
FORCEPROP 0 LASTPIN (-2675 3650) $PN 211
J 2
(-2685 3660);
DISPLAY 0.680851 (-2685 3660);
PAINT MONO (-2685 3660);
FORCEPROP 0 LASTPIN (-2675 3250) $PN 221
J 2
(-2685 3260);
DISPLAY 0.680851 (-2685 3260);
PAINT MONO (-2685 3260);
FORCEPROP 0 LASTPIN (-2675 3700) $PN 68
J 2
(-2685 3710);
DISPLAY 0.680851 (-2685 3710);
PAINT MONO (-2685 3710);
FORCEPROP 0 LASTPIN (-2675 3300) $PN 78
J 2
(-2685 3310);
DISPLAY 0.680851 (-2685 3310);
PAINT MONO (-2685 3310);
FORCEPROP 0 LASTPIN (-2675 3750) $PN 213
J 2
(-2685 3760);
DISPLAY 0.680851 (-2685 3760);
PAINT MONO (-2685 3760);
FORCEPROP 0 LASTPIN (-2675 3350) $PN 223
J 2
(-2685 3360);
DISPLAY 0.680851 (-2685 3360);
PAINT MONO (-2685 3360);
FORCEPROP 0 LASTPIN (-2675 3800) $PN 70
J 2
(-2685 3810);
DISPLAY 0.680851 (-2685 3810);
PAINT MONO (-2685 3810);
FORCEPROP 0 LASTPIN (-2675 3400) $PN 80
J 2
(-2685 3410);
DISPLAY 0.680851 (-2685 3410);
PAINT MONO (-2685 3410);
FORCEPROP 0 LASTPIN (-2675 3850) $PN 215
J 2
(-2685 3860);
DISPLAY 0.680851 (-2685 3860);
PAINT MONO (-2685 3860);
FORCEPROP 0 LASTPIN (-2675 3450) $PN 225
J 2
(-2685 3460);
DISPLAY 0.680851 (-2685 3460);
PAINT MONO (-2685 3460);
FORCEPROP 0 LASTPIN (-2675 3900) $PN 72
J 2
(-2685 3910);
DISPLAY 0.680851 (-2685 3910);
PAINT MONO (-2685 3910);
FORCEPROP 0 LASTPIN (-2675 3500) $PN 82
J 2
(-2685 3510);
DISPLAY 0.680851 (-2685 3510);
PAINT MONO (-2685 3510);
FORCEPROP 0 LASTPIN (-2675 2150) $PN 51
J 2
(-2685 2160);
DISPLAY 0.680851 (-2685 2160);
PAINT MONO (-2685 2160);
FORCEPROP 0 LASTPIN (-2675 1700) $PN 96
J 2
(-2685 1710);
DISPLAY 0.680851 (-2685 1710);
PAINT MONO (-2685 1710);
FORCEPROP 0 LASTPIN (-2675 2200) $PN 53
J 2
(-2685 2210);
DISPLAY 0.680851 (-2685 2210);
PAINT MONO (-2685 2210);
FORCEPROP 0 LASTPIN (-2675 1750) $PN 98
J 2
(-2685 1760);
DISPLAY 0.680851 (-2685 1760);
PAINT MONO (-2685 1760);
FORCEPROP 0 LASTPIN (-2675 2250) $PN 196
J 2
(-2685 2260);
DISPLAY 0.680851 (-2685 2260);
PAINT MONO (-2685 2260);
FORCEPROP 0 LASTPIN (-2675 1800) $PN 241
J 2
(-2685 1810);
DISPLAY 0.680851 (-2685 1810);
PAINT MONO (-2685 1810);
FORCEPROP 0 LASTPIN (-2675 2300) $PN 198
J 2
(-2685 2310);
DISPLAY 0.680851 (-2685 2310);
PAINT MONO (-2685 2310);
FORCEPROP 0 LASTPIN (-2675 1850) $PN 243
J 2
(-2685 1860);
DISPLAY 0.680851 (-2685 1860);
PAINT MONO (-2685 1860);
FORCEPROP 0 LASTPIN (-2675 2350) $PN 58
J 2
(-2685 2360);
DISPLAY 0.680851 (-2685 2360);
PAINT MONO (-2685 2360);
FORCEPROP 0 LASTPIN (-2675 1900) $PN 89
J 2
(-2685 1910);
DISPLAY 0.680851 (-2685 1910);
PAINT MONO (-2685 1910);
FORCEPROP 0 LASTPIN (-2675 2400) $PN 60
J 2
(-2685 2410);
DISPLAY 0.680851 (-2685 2410);
PAINT MONO (-2685 2410);
FORCEPROP 0 LASTPIN (-2675 1950) $PN 91
J 2
(-2685 1960);
DISPLAY 0.680851 (-2685 1960);
PAINT MONO (-2685 1960);
FORCEPROP 0 LASTPIN (-2675 2450) $PN 203
J 2
(-2685 2460);
DISPLAY 0.680851 (-2685 2460);
PAINT MONO (-2685 2460);
FORCEPROP 0 LASTPIN (-2675 2000) $PN 234
J 2
(-2685 2010);
DISPLAY 0.680851 (-2685 2010);
PAINT MONO (-2685 2010);
FORCEPROP 0 LASTPIN (-2675 2500) $PN 205
J 2
(-2685 2510);
DISPLAY 0.680851 (-2685 2510);
PAINT MONO (-2685 2510);
FORCEPROP 0 LASTPIN (-2675 2050) $PN 236
J 2
(-2685 2060);
DISPLAY 0.680851 (-2685 2060);
PAINT MONO (-2685 2060);
FORCEPROP 0 LASTPIN (-2675 2600) $PN 218
J 2
(-2685 2610);
DISPLAY 0.680851 (-2685 2610);
PAINT MONO (-2685 2610);
FORCEPROP 0 LASTPIN (-2675 2650) $PN 217
J 2
(-2685 2660);
DISPLAY 0.680851 (-2685 2660);
PAINT MONO (-2685 2660);
FORCEPROP 0 LASTPIN (-2675 2900) $PN 64
J 2
(-2685 2910);
DISPLAY 0.680851 (-2685 2910);
PAINT MONO (-2685 2910);
FORCEPROP 0 LASTPIN (-2675 2750) $PN 84
J 2
(-2685 2760);
DISPLAY 0.680851 (-2685 2760);
PAINT MONO (-2685 2760);
FORCEPROP 0 LASTPIN (-2675 2950) $PN 209
J 2
(-2685 2960);
DISPLAY 0.680851 (-2685 2960);
PAINT MONO (-2685 2960);
FORCEPROP 0 LASTPIN (-2675 2800) $PN 229
J 2
(-2685 2810);
DISPLAY 0.680851 (-2685 2810);
PAINT MONO (-2685 2810);
FORCEPROP 0 LASTPIN (-1475 2350) $PN 7
J 0
(-1465 2360);
DISPLAY 0.680851 (-1465 2360);
PAINT MONO (-1465 2360);
FORCEPROP 0 LASTPIN (-1475 700) $PN 100
J 0
(-1465 710);
DISPLAY 0.680851 (-1465 710);
PAINT MONO (-1465 710);
FORCEPROP 0 LASTPIN (-1475 2400) $PN 9
J 0
(-1465 2410);
DISPLAY 0.680851 (-1465 2410);
PAINT MONO (-1465 2410);
FORCEPROP 0 LASTPIN (-1475 750) $PN 102
J 0
(-1465 760);
DISPLAY 0.680851 (-1465 760);
PAINT MONO (-1465 760);
FORCEPROP 0 LASTPIN (-1475 2450) $PN 152
J 0
(-1465 2460);
DISPLAY 0.680851 (-1465 2460);
PAINT MONO (-1465 2460);
FORCEPROP 0 LASTPIN (-1475 800) $PN 245
J 0
(-1465 810);
DISPLAY 0.680851 (-1465 810);
PAINT MONO (-1465 810);
FORCEPROP 0 LASTPIN (-1475 2500) $PN 154
J 0
(-1465 2510);
DISPLAY 0.680851 (-1465 2510);
PAINT MONO (-1465 2510);
FORCEPROP 0 LASTPIN (-1475 850) $PN 247
J 0
(-1465 860);
DISPLAY 0.680851 (-1465 860);
PAINT MONO (-1465 860);
FORCEPROP 0 LASTPIN (-1475 2550) $PN 14
J 0
(-1465 2560);
DISPLAY 0.680851 (-1465 2560);
PAINT MONO (-1465 2560);
FORCEPROP 0 LASTPIN (-1475 900) $PN 107
J 0
(-1465 910);
DISPLAY 0.680851 (-1465 910);
PAINT MONO (-1465 910);
FORCEPROP 0 LASTPIN (-1475 2600) $PN 16
J 0
(-1465 2610);
DISPLAY 0.680851 (-1465 2610);
PAINT MONO (-1465 2610);
FORCEPROP 0 LASTPIN (-1475 950) $PN 109
J 0
(-1465 960);
DISPLAY 0.680851 (-1465 960);
PAINT MONO (-1465 960);
FORCEPROP 0 LASTPIN (-1475 2650) $PN 159
J 0
(-1465 2660);
DISPLAY 0.680851 (-1465 2660);
PAINT MONO (-1465 2660);
FORCEPROP 0 LASTPIN (-1475 1000) $PN 252
J 0
(-1465 1010);
DISPLAY 0.680851 (-1465 1010);
PAINT MONO (-1465 1010);
FORCEPROP 0 LASTPIN (-1475 2700) $PN 161
J 0
(-1465 2710);
DISPLAY 0.680851 (-1465 2710);
PAINT MONO (-1465 2710);
FORCEPROP 0 LASTPIN (-1475 1050) $PN 254
J 0
(-1465 1060);
DISPLAY 0.680851 (-1465 1060);
PAINT MONO (-1465 1060);
FORCEPROP 0 LASTPIN (-1475 2750) $PN 18
J 0
(-1465 2760);
DISPLAY 0.680851 (-1465 2760);
PAINT MONO (-1465 2760);
FORCEPROP 0 LASTPIN (-1475 1100) $PN 111
J 0
(-1465 1110);
DISPLAY 0.680851 (-1465 1110);
PAINT MONO (-1465 1110);
FORCEPROP 0 LASTPIN (-1475 2800) $PN 20
J 0
(-1465 2810);
DISPLAY 0.680851 (-1465 2810);
PAINT MONO (-1465 2810);
FORCEPROP 0 LASTPIN (-1475 1150) $PN 113
J 0
(-1465 1160);
DISPLAY 0.680851 (-1465 1160);
PAINT MONO (-1465 1160);
FORCEPROP 0 LASTPIN (-1475 2850) $PN 163
J 0
(-1465 2860);
DISPLAY 0.680851 (-1465 2860);
PAINT MONO (-1465 2860);
FORCEPROP 0 LASTPIN (-1475 1200) $PN 256
J 0
(-1465 1210);
DISPLAY 0.680851 (-1465 1210);
PAINT MONO (-1465 1210);
FORCEPROP 0 LASTPIN (-1475 2900) $PN 165
J 0
(-1465 2910);
DISPLAY 0.680851 (-1465 2910);
PAINT MONO (-1465 2910);
FORCEPROP 0 LASTPIN (-1475 1250) $PN 258
J 0
(-1465 1260);
DISPLAY 0.680851 (-1465 1260);
PAINT MONO (-1465 1260);
FORCEPROP 0 LASTPIN (-1475 2950) $PN 25
J 0
(-1465 2960);
DISPLAY 0.680851 (-1465 2960);
PAINT MONO (-1465 2960);
FORCEPROP 0 LASTPIN (-1475 1300) $PN 118
J 0
(-1465 1310);
DISPLAY 0.680851 (-1465 1310);
PAINT MONO (-1465 1310);
FORCEPROP 0 LASTPIN (-1475 3000) $PN 27
J 0
(-1465 3010);
DISPLAY 0.680851 (-1465 3010);
PAINT MONO (-1465 3010);
FORCEPROP 0 LASTPIN (-1475 1350) $PN 120
J 0
(-1465 1360);
DISPLAY 0.680851 (-1465 1360);
PAINT MONO (-1465 1360);
FORCEPROP 0 LASTPIN (-1475 3050) $PN 170
J 0
(-1465 3060);
DISPLAY 0.680851 (-1465 3060);
PAINT MONO (-1465 3060);
FORCEPROP 0 LASTPIN (-1475 1400) $PN 263
J 0
(-1465 1410);
DISPLAY 0.680851 (-1465 1410);
PAINT MONO (-1465 1410);
FORCEPROP 0 LASTPIN (-1475 3100) $PN 172
J 0
(-1465 3110);
DISPLAY 0.680851 (-1465 3110);
PAINT MONO (-1465 3110);
FORCEPROP 0 LASTPIN (-1475 1450) $PN 265
J 0
(-1465 1460);
DISPLAY 0.680851 (-1465 1460);
PAINT MONO (-1465 1460);
FORCEPROP 0 LASTPIN (-1475 3150) $PN 29
J 0
(-1465 3160);
DISPLAY 0.680851 (-1465 3160);
PAINT MONO (-1465 3160);
FORCEPROP 0 LASTPIN (-1475 1500) $PN 122
J 0
(-1465 1510);
DISPLAY 0.680851 (-1465 1510);
PAINT MONO (-1465 1510);
FORCEPROP 0 LASTPIN (-1475 3200) $PN 31
J 0
(-1465 3210);
DISPLAY 0.680851 (-1465 3210);
PAINT MONO (-1465 3210);
FORCEPROP 0 LASTPIN (-1475 1550) $PN 124
J 0
(-1465 1560);
DISPLAY 0.680851 (-1465 1560);
PAINT MONO (-1465 1560);
FORCEPROP 0 LASTPIN (-1475 3250) $PN 174
J 0
(-1465 3260);
DISPLAY 0.680851 (-1465 3260);
PAINT MONO (-1465 3260);
FORCEPROP 0 LASTPIN (-1475 1600) $PN 267
J 0
(-1465 1610);
DISPLAY 0.680851 (-1465 1610);
PAINT MONO (-1465 1610);
FORCEPROP 0 LASTPIN (-1475 3300) $PN 176
J 0
(-1465 3310);
DISPLAY 0.680851 (-1465 3310);
PAINT MONO (-1465 3310);
FORCEPROP 0 LASTPIN (-1475 1650) $PN 269
J 0
(-1465 1660);
DISPLAY 0.680851 (-1465 1660);
PAINT MONO (-1465 1660);
FORCEPROP 0 LASTPIN (-1475 3350) $PN 36
J 0
(-1465 3360);
DISPLAY 0.680851 (-1465 3360);
PAINT MONO (-1465 3360);
FORCEPROP 0 LASTPIN (-1475 1700) $PN 129
J 0
(-1465 1710);
DISPLAY 0.680851 (-1465 1710);
PAINT MONO (-1465 1710);
FORCEPROP 0 LASTPIN (-1475 3400) $PN 38
J 0
(-1465 3410);
DISPLAY 0.680851 (-1465 3410);
PAINT MONO (-1465 3410);
FORCEPROP 0 LASTPIN (-1475 1750) $PN 131
J 0
(-1465 1760);
DISPLAY 0.680851 (-1465 1760);
PAINT MONO (-1465 1760);
FORCEPROP 0 LASTPIN (-1475 3450) $PN 181
J 0
(-1465 3460);
DISPLAY 0.680851 (-1465 3460);
PAINT MONO (-1465 3460);
FORCEPROP 0 LASTPIN (-1475 1800) $PN 274
J 0
(-1465 1810);
DISPLAY 0.680851 (-1465 1810);
PAINT MONO (-1465 1810);
FORCEPROP 0 LASTPIN (-1475 3500) $PN 183
J 0
(-1465 3510);
DISPLAY 0.680851 (-1465 3510);
PAINT MONO (-1465 3510);
FORCEPROP 0 LASTPIN (-1475 1850) $PN 276
J 0
(-1465 1860);
DISPLAY 0.680851 (-1465 1860);
PAINT MONO (-1465 1860);
FORCEPROP 0 LASTPIN (-1475 3550) $PN 40
J 0
(-1465 3560);
DISPLAY 0.680851 (-1465 3560);
PAINT MONO (-1465 3560);
FORCEPROP 0 LASTPIN (-1475 1900) $PN 133
J 0
(-1465 1910);
DISPLAY 0.680851 (-1465 1910);
PAINT MONO (-1465 1910);
FORCEPROP 0 LASTPIN (-1475 3600) $PN 42
J 0
(-1465 3610);
DISPLAY 0.680851 (-1465 3610);
PAINT MONO (-1465 3610);
FORCEPROP 0 LASTPIN (-1475 1950) $PN 135
J 0
(-1465 1960);
DISPLAY 0.680851 (-1465 1960);
PAINT MONO (-1465 1960);
FORCEPROP 0 LASTPIN (-1475 3650) $PN 185
J 0
(-1465 3660);
DISPLAY 0.680851 (-1465 3660);
PAINT MONO (-1465 3660);
FORCEPROP 0 LASTPIN (-1475 2000) $PN 278
J 0
(-1465 2010);
DISPLAY 0.680851 (-1465 2010);
PAINT MONO (-1465 2010);
FORCEPROP 0 LASTPIN (-1475 3700) $PN 187
J 0
(-1465 3710);
DISPLAY 0.680851 (-1465 3710);
PAINT MONO (-1465 3710);
FORCEPROP 0 LASTPIN (-1475 2050) $PN 280
J 0
(-1465 2060);
DISPLAY 0.680851 (-1465 2060);
PAINT MONO (-1465 2060);
FORCEPROP 0 LASTPIN (-1475 3750) $PN 47
J 0
(-1465 3760);
DISPLAY 0.680851 (-1465 3760);
PAINT MONO (-1465 3760);
FORCEPROP 0 LASTPIN (-1475 2100) $PN 140
J 0
(-1465 2110);
DISPLAY 0.680851 (-1465 2110);
PAINT MONO (-1465 2110);
FORCEPROP 0 LASTPIN (-1475 3800) $PN 49
J 0
(-1465 3810);
DISPLAY 0.680851 (-1465 3810);
PAINT MONO (-1465 3810);
FORCEPROP 0 LASTPIN (-1475 2150) $PN 142
J 0
(-1465 2160);
DISPLAY 0.680851 (-1465 2160);
PAINT MONO (-1465 2160);
FORCEPROP 0 LASTPIN (-1475 3850) $PN 192
J 0
(-1465 3860);
DISPLAY 0.680851 (-1465 3860);
PAINT MONO (-1465 3860);
FORCEPROP 0 LASTPIN (-1475 2200) $PN 285
J 0
(-1465 2210);
DISPLAY 0.680851 (-1465 2210);
PAINT MONO (-1465 2210);
FORCEPROP 0 LASTPIN (-1475 3900) $PN 194
J 0
(-1465 3910);
DISPLAY 0.680851 (-1465 3910);
PAINT MONO (-1465 3910);
FORCEPROP 0 LASTPIN (-1475 2250) $PN 287
J 0
(-1465 2260);
DISPLAY 0.680851 (-1465 2260);
PAINT MONO (-1465 2260);
FORCEPROP 0 LASTPIN (-2675 1400) $PN 148
J 2
(-2685 1410);
DISPLAY 0.680851 (-2685 1410);
PAINT MONO (-2685 1410);
FORCEPROP 0 LASTPIN (-2675 1300) $PN 4
J 2
(-2685 1310);
DISPLAY 0.680851 (-2685 1310);
PAINT MONO (-2685 1310);
FORCEPROP 0 LASTPIN (-2675 1350) $PN 5
J 2
(-2685 1360);
DISPLAY 0.680851 (-2685 1360);
PAINT MONO (-2685 1360);
FORCEPROP 0 LASTPIN (-2675 500) $PN 86
J 2
(-2685 510);
DISPLAY 0.680851 (-2685 510);
PAINT MONO (-2685 510);
FORCEPROP 0 LASTPIN (-2675 450) $PN 87
J 2
(-2685 460);
DISPLAY 0.680851 (-2685 460);
PAINT MONO (-2685 460);
FORCEPROP 0 LASTPIN (-2675 3100) $PN 74
J 2
(-2685 3110);
DISPLAY 0.680851 (-2685 3110);
PAINT MONO (-2685 3110);
FORCEPROP 0 LASTPIN (-2675 3050) $PN 227
J 2
(-2685 3060);
DISPLAY 0.680851 (-2685 3060);
PAINT MONO (-2685 3060);
FORCEPROP 0 LASTPIN (-2675 1050) $PN 147
J 2
(-2685 1060);
DISPLAY 0.680851 (-2685 1060);
PAINT MONO (-2685 1060);
FORCEPROP 0 LASTPIN (-2675 1600) $PN 207
J 2
(-2685 1610);
DISPLAY 0.680851 (-2685 1610);
PAINT MONO (-2685 1610);
FORCEPROP 0 LASTPIN (-2675 650) $PN 2
J 2
(-2685 660);
DISPLAY 0.680851 (-2685 660);
PAINT MONO (-2685 660);
FORCEPROP 0 LASTPIN (-2675 700) $PN 144
J 2
(-2685 710);
DISPLAY 0.680851 (-2685 710);
PAINT MONO (-2685 710);
FORCEPROP 0 LASTPIN (-2675 750) $PN 149
J 2
(-2685 760);
DISPLAY 0.680851 (-2685 760);
PAINT MONO (-2685 760);
FORCEPROP 0 LASTPIN (-2675 800) $PN 150
J 2
(-2685 810);
DISPLAY 0.680851 (-2685 810);
PAINT MONO (-2685 810);
FORCEPROP 0 LASTPIN (-2675 850) $PN 220
J 2
(-2685 860);
DISPLAY 0.680851 (-2685 860);
PAINT MONO (-2685 860);
FORCEPROP 0 LASTPIN (-2675 900) $PN 231
J 2
(-2685 910);
DISPLAY 0.680851 (-2685 910);
PAINT MONO (-2685 910);
FORCEPROP 0 LASTPIN (-2675 950) $PN 232
J 2
(-2685 960);
DISPLAY 0.680851 (-2685 960);
PAINT MONO (-2685 960);
FORCEPROP 0 LASTPIN (-2675 1450) $PN 3
J 2
(-2685 1460);
DISPLAY 0.680851 (-2685 1460);
PAINT MONO (-2685 1460);
FORCEPROP 1 LAST NEEDS_NO_SIZE TRUE
J 0
(-2075 2175);
DISPLAY 0.723404 (-2075 2175);
PAINT GREEN (-2075 2175);
DISPLAY INVISIBLE (-2075 2175);
FORCEPROP 1 LAST CDS_LMAN_SYM_OUTLINE -450,1875,450,-1875
J 0
(-2075 2175);
DISPLAY 0.468085 (-2075 2175);
PAINT GREEN (-2075 2175);
DISPLAY INVISIBLE (-2075 2175);
FORCEPROP 2 LAST CDS_LIB pure_quanta
J 0
(-2075 2175);
DISPLAY INVISIBLE (-2075 2175);
FORCEPROP 1 LAST PATH I51
J 0
(-2075 2175);
DISPLAY 0.723404 (-2075 2175);
PAINT GREEN (-2075 2175);
DISPLAY INVISIBLE (-2075 2175);
FORCEPROP 2 LAST CDS_LOCATION J22
J 0
(-2525 4400);
DISPLAY 1.021277 (-2525 4400);
DISPLAY INVISIBLE (-2525 4400);
FORCEPROP 0 LAST $SEC 1
J 0
(-2525 4400);
DISPLAY 0.680851 (-2525 4400);
PAINT MONO (-2525 4400);
DISPLAY INVISIBLE (-2525 4400);
FORCEPROP 2 LAST CDS_SEC 1
J 0
(-2525 4400);
DISPLAY 1.021277 (-2525 4400);
DISPLAY INVISIBLE (-2525 4400);
FORCEADD TAP..1
(-1250 700);
FORCEPROP 3 LASTPIN (-1300 700) SIG_NAME M_C_CPU1_SB_DQ<0>
J 0
(-1290 710);
DISPLAY 0.659574 (-1290 710);
PAINT MONO (-1290 710);
DISPLAY INVISIBLE (-1290 710);
FORCEPROP 1 LASTPIN (-1300 700) BN 0
J 0
(-1312 708);
DISPLAY 0.680851 (-1312 708);
PAINT GREEN (-1312 708);
FORCEPROP 2 LAST CDS_LIB standard
J 0
(-1250 700);
PAINT MONO (-1250 700);
DISPLAY INVISIBLE (-1250 700);
FORCEPROP 1 LAST BODY_TYPE PLUMBING
J 0
(-1250 750);
DISPLAY 0.872340 (-1250 750);
PAINT GREEN (-1250 750);
DISPLAY INVISIBLE (-1250 750);
FORCEPROP 1 LAST HDL_TAP TRUE
J 0
(-925 575);
DISPLAY 0.872340 (-925 575);
DISPLAY INVISIBLE (-925 575);
FORCEPROP 1 LAST PATH I52
J 0
(-1252 700);
DISPLAY 0.872340 (-1252 700);
PAINT GREEN (-1252 700);
DISPLAY INVISIBLE (-1252 700);
FORCEADD TAP..1
(-1250 750);
FORCEPROP 3 LASTPIN (-1300 750) SIG_NAME M_C_CPU1_SB_DQ<1>
J 0
(-1290 760);
DISPLAY 0.659574 (-1290 760);
PAINT MONO (-1290 760);
DISPLAY INVISIBLE (-1290 760);
FORCEPROP 1 LASTPIN (-1300 750) BN 1
J 0
(-1312 758);
DISPLAY 0.680851 (-1312 758);
PAINT GREEN (-1312 758);
FORCEPROP 2 LAST CDS_LIB standard
J 0
(-1250 750);
PAINT MONO (-1250 750);
DISPLAY INVISIBLE (-1250 750);
FORCEPROP 1 LAST BODY_TYPE PLUMBING
J 0
(-1250 800);
DISPLAY 0.872340 (-1250 800);
PAINT GREEN (-1250 800);
DISPLAY INVISIBLE (-1250 800);
FORCEPROP 1 LAST HDL_TAP TRUE
J 0
(-925 625);
DISPLAY 0.872340 (-925 625);
DISPLAY INVISIBLE (-925 625);
FORCEPROP 1 LAST PATH I53
J 0
(-1252 750);
DISPLAY 0.872340 (-1252 750);
PAINT GREEN (-1252 750);
DISPLAY INVISIBLE (-1252 750);
FORCEADD TAP..1
(-1250 850);
FORCEPROP 3 LASTPIN (-1300 850) SIG_NAME M_C_CPU1_SB_DQ<3>
J 0
(-1290 860);
DISPLAY 0.659574 (-1290 860);
PAINT MONO (-1290 860);
DISPLAY INVISIBLE (-1290 860);
FORCEPROP 1 LASTPIN (-1300 850) BN 3
J 0
(-1312 858);
DISPLAY 0.680851 (-1312 858);
PAINT GREEN (-1312 858);
FORCEPROP 2 LAST CDS_LIB standard
J 0
(-1250 850);
PAINT MONO (-1250 850);
DISPLAY INVISIBLE (-1250 850);
FORCEPROP 1 LAST BODY_TYPE PLUMBING
J 0
(-1250 900);
DISPLAY 0.872340 (-1250 900);
PAINT GREEN (-1250 900);
DISPLAY INVISIBLE (-1250 900);
FORCEPROP 1 LAST HDL_TAP TRUE
J 0
(-925 725);
DISPLAY 0.872340 (-925 725);
DISPLAY INVISIBLE (-925 725);
FORCEPROP 1 LAST PATH I54
J 0
(-1252 850);
DISPLAY 0.872340 (-1252 850);
PAINT GREEN (-1252 850);
DISPLAY INVISIBLE (-1252 850);
FORCEADD TAP..1
(-1250 800);
FORCEPROP 3 LASTPIN (-1300 800) SIG_NAME M_C_CPU1_SB_DQ<2>
J 0
(-1290 810);
DISPLAY 0.659574 (-1290 810);
PAINT MONO (-1290 810);
DISPLAY INVISIBLE (-1290 810);
FORCEPROP 1 LASTPIN (-1300 800) BN 2
J 0
(-1312 808);
DISPLAY 0.680851 (-1312 808);
PAINT GREEN (-1312 808);
FORCEPROP 2 LAST CDS_LIB standard
J 0
(-1250 800);
PAINT MONO (-1250 800);
DISPLAY INVISIBLE (-1250 800);
FORCEPROP 1 LAST BODY_TYPE PLUMBING
J 0
(-1250 850);
DISPLAY 0.872340 (-1250 850);
PAINT GREEN (-1250 850);
DISPLAY INVISIBLE (-1250 850);
FORCEPROP 1 LAST HDL_TAP TRUE
J 0
(-925 675);
DISPLAY 0.872340 (-925 675);
DISPLAY INVISIBLE (-925 675);
FORCEPROP 1 LAST PATH I55
J 0
(-1252 800);
DISPLAY 0.872340 (-1252 800);
PAINT GREEN (-1252 800);
DISPLAY INVISIBLE (-1252 800);
FORCEADD TAP..1
(-1250 900);
FORCEPROP 3 LASTPIN (-1300 900) SIG_NAME M_C_CPU1_SB_DQ<4>
J 0
(-1290 910);
DISPLAY 0.659574 (-1290 910);
PAINT MONO (-1290 910);
DISPLAY INVISIBLE (-1290 910);
FORCEPROP 1 LASTPIN (-1300 900) BN 4
J 0
(-1312 908);
DISPLAY 0.680851 (-1312 908);
PAINT GREEN (-1312 908);
FORCEPROP 2 LAST CDS_LIB standard
J 0
(-1250 900);
PAINT MONO (-1250 900);
DISPLAY INVISIBLE (-1250 900);
FORCEPROP 1 LAST BODY_TYPE PLUMBING
J 0
(-1250 950);
DISPLAY 0.872340 (-1250 950);
PAINT GREEN (-1250 950);
DISPLAY INVISIBLE (-1250 950);
FORCEPROP 1 LAST HDL_TAP TRUE
J 0
(-925 775);
DISPLAY 0.872340 (-925 775);
DISPLAY INVISIBLE (-925 775);
FORCEPROP 1 LAST PATH I56
J 0
(-1252 900);
DISPLAY 0.872340 (-1252 900);
PAINT GREEN (-1252 900);
DISPLAY INVISIBLE (-1252 900);
FORCEADD TAP..1
(-1250 950);
FORCEPROP 3 LASTPIN (-1300 950) SIG_NAME M_C_CPU1_SB_DQ<5>
J 0
(-1290 960);
DISPLAY 0.659574 (-1290 960);
PAINT MONO (-1290 960);
DISPLAY INVISIBLE (-1290 960);
FORCEPROP 1 LASTPIN (-1300 950) BN 5
J 0
(-1312 958);
DISPLAY 0.680851 (-1312 958);
PAINT GREEN (-1312 958);
FORCEPROP 2 LAST CDS_LIB standard
J 0
(-1250 950);
PAINT MONO (-1250 950);
DISPLAY INVISIBLE (-1250 950);
FORCEPROP 1 LAST BODY_TYPE PLUMBING
J 0
(-1250 1000);
DISPLAY 0.872340 (-1250 1000);
PAINT GREEN (-1250 1000);
DISPLAY INVISIBLE (-1250 1000);
FORCEPROP 1 LAST HDL_TAP TRUE
J 0
(-925 825);
DISPLAY 0.872340 (-925 825);
DISPLAY INVISIBLE (-925 825);
FORCEPROP 1 LAST PATH I57
J 0
(-1252 950);
DISPLAY 0.872340 (-1252 950);
PAINT GREEN (-1252 950);
DISPLAY INVISIBLE (-1252 950);
FORCEADD TAP..1
(-1250 1000);
FORCEPROP 3 LASTPIN (-1300 1000) SIG_NAME M_C_CPU1_SB_DQ<6>
J 0
(-1290 1010);
DISPLAY 0.659574 (-1290 1010);
PAINT MONO (-1290 1010);
DISPLAY INVISIBLE (-1290 1010);
FORCEPROP 1 LASTPIN (-1300 1000) BN 6
J 0
(-1312 1008);
DISPLAY 0.680851 (-1312 1008);
PAINT GREEN (-1312 1008);
FORCEPROP 2 LAST CDS_LIB standard
J 0
(-1250 1000);
PAINT MONO (-1250 1000);
DISPLAY INVISIBLE (-1250 1000);
FORCEPROP 1 LAST BODY_TYPE PLUMBING
J 0
(-1250 1050);
DISPLAY 0.872340 (-1250 1050);
PAINT GREEN (-1250 1050);
DISPLAY INVISIBLE (-1250 1050);
FORCEPROP 1 LAST HDL_TAP TRUE
J 0
(-925 875);
DISPLAY 0.872340 (-925 875);
DISPLAY INVISIBLE (-925 875);
FORCEPROP 1 LAST PATH I58
J 0
(-1252 1000);
DISPLAY 0.872340 (-1252 1000);
PAINT GREEN (-1252 1000);
DISPLAY INVISIBLE (-1252 1000);
FORCEADD TAP..1
(-1250 1100);
FORCEPROP 3 LASTPIN (-1300 1100) SIG_NAME M_C_CPU1_SB_DQ<8>
J 0
(-1290 1110);
DISPLAY 0.659574 (-1290 1110);
PAINT MONO (-1290 1110);
DISPLAY INVISIBLE (-1290 1110);
FORCEPROP 1 LASTPIN (-1300 1100) BN 8
J 0
(-1312 1108);
DISPLAY 0.680851 (-1312 1108);
PAINT GREEN (-1312 1108);
FORCEPROP 2 LAST CDS_LIB standard
J 0
(-1250 1100);
PAINT MONO (-1250 1100);
DISPLAY INVISIBLE (-1250 1100);
FORCEPROP 1 LAST BODY_TYPE PLUMBING
J 0
(-1250 1150);
DISPLAY 0.872340 (-1250 1150);
PAINT GREEN (-1250 1150);
DISPLAY INVISIBLE (-1250 1150);
FORCEPROP 1 LAST HDL_TAP TRUE
J 0
(-925 975);
DISPLAY 0.872340 (-925 975);
DISPLAY INVISIBLE (-925 975);
FORCEPROP 1 LAST PATH I59
J 0
(-1252 1100);
DISPLAY 0.872340 (-1252 1100);
PAINT GREEN (-1252 1100);
DISPLAY INVISIBLE (-1252 1100);
FORCEADD OFFPAGE..3
R 2
(-3825 1050);
FORCEPROP 2 LAST $XR0 114 
J 0
(-4105 1050);
DISPLAY 0.638298 (-4105 1050);
PAINT MONO (-4105 1050);
FORCEPROP 2 LAST CDS_LIB standard
J 0
(-3825 1050);
PAINT MONO (-3825 1050);
DISPLAY INVISIBLE (-3825 1050);
FORCEPROP 1 LAST OFFPAGE TRUE
J 2
(-4150 925);
DISPLAY 0.872340 (-4150 925);
DISPLAY INVISIBLE (-4150 925);
FORCEPROP 1 LAST COMMENT_BODY TRUE
J 2
(-3775 950);
DISPLAY 0.872340 (-3775 950);
PAINT GREEN (-3775 950);
DISPLAY INVISIBLE (-3775 950);
FORCEPROP 2 LAST PATH I6
J 0
(-3775 1125);
DISPLAY 1.021277 (-3775 1125);
DISPLAY INVISIBLE (-3775 1125);
FORCEADD TAP..1
(-1250 1050);
FORCEPROP 3 LASTPIN (-1300 1050) SIG_NAME M_C_CPU1_SB_DQ<7>
J 0
(-1290 1060);
DISPLAY 0.659574 (-1290 1060);
PAINT MONO (-1290 1060);
DISPLAY INVISIBLE (-1290 1060);
FORCEPROP 1 LASTPIN (-1300 1050) BN 7
J 0
(-1312 1058);
DISPLAY 0.680851 (-1312 1058);
PAINT GREEN (-1312 1058);
FORCEPROP 2 LAST CDS_LIB standard
J 0
(-1250 1050);
PAINT MONO (-1250 1050);
DISPLAY INVISIBLE (-1250 1050);
FORCEPROP 1 LAST BODY_TYPE PLUMBING
J 0
(-1250 1100);
DISPLAY 0.872340 (-1250 1100);
PAINT GREEN (-1250 1100);
DISPLAY INVISIBLE (-1250 1100);
FORCEPROP 1 LAST HDL_TAP TRUE
J 0
(-925 925);
DISPLAY 0.872340 (-925 925);
DISPLAY INVISIBLE (-925 925);
FORCEPROP 1 LAST PATH I60
J 0
(-1252 1050);
DISPLAY 0.872340 (-1252 1050);
PAINT GREEN (-1252 1050);
DISPLAY INVISIBLE (-1252 1050);
FORCEADD TAP..1
(-1250 1150);
FORCEPROP 3 LASTPIN (-1300 1150) SIG_NAME M_C_CPU1_SB_DQ<9>
J 0
(-1290 1160);
DISPLAY 0.659574 (-1290 1160);
PAINT MONO (-1290 1160);
DISPLAY INVISIBLE (-1290 1160);
FORCEPROP 1 LASTPIN (-1300 1150) BN 9
J 0
(-1312 1158);
DISPLAY 0.680851 (-1312 1158);
PAINT GREEN (-1312 1158);
FORCEPROP 2 LAST CDS_LIB standard
J 0
(-1250 1150);
PAINT MONO (-1250 1150);
DISPLAY INVISIBLE (-1250 1150);
FORCEPROP 1 LAST BODY_TYPE PLUMBING
J 0
(-1250 1200);
DISPLAY 0.872340 (-1250 1200);
PAINT GREEN (-1250 1200);
DISPLAY INVISIBLE (-1250 1200);
FORCEPROP 1 LAST HDL_TAP TRUE
J 0
(-925 1025);
DISPLAY 0.872340 (-925 1025);
DISPLAY INVISIBLE (-925 1025);
FORCEPROP 1 LAST PATH I61
J 0
(-1252 1150);
DISPLAY 0.872340 (-1252 1150);
PAINT GREEN (-1252 1150);
DISPLAY INVISIBLE (-1252 1150);
FORCEADD TAP..1
(-1250 1200);
FORCEPROP 3 LASTPIN (-1300 1200) SIG_NAME M_C_CPU1_SB_DQ<10>
J 0
(-1290 1210);
DISPLAY 0.659574 (-1290 1210);
PAINT MONO (-1290 1210);
DISPLAY INVISIBLE (-1290 1210);
FORCEPROP 1 LASTPIN (-1300 1200) BN 10
J 0
(-1312 1208);
DISPLAY 0.680851 (-1312 1208);
PAINT GREEN (-1312 1208);
FORCEPROP 2 LAST CDS_LIB standard
J 0
(-1250 1200);
PAINT MONO (-1250 1200);
DISPLAY INVISIBLE (-1250 1200);
FORCEPROP 1 LAST BODY_TYPE PLUMBING
J 0
(-1250 1250);
DISPLAY 0.872340 (-1250 1250);
PAINT GREEN (-1250 1250);
DISPLAY INVISIBLE (-1250 1250);
FORCEPROP 1 LAST HDL_TAP TRUE
J 0
(-925 1075);
DISPLAY 0.872340 (-925 1075);
DISPLAY INVISIBLE (-925 1075);
FORCEPROP 1 LAST PATH I62
J 0
(-1252 1200);
DISPLAY 0.872340 (-1252 1200);
PAINT GREEN (-1252 1200);
DISPLAY INVISIBLE (-1252 1200);
FORCEADD TAP..1
(-1250 1250);
FORCEPROP 3 LASTPIN (-1300 1250) SIG_NAME M_C_CPU1_SB_DQ<11>
J 0
(-1290 1260);
DISPLAY 0.659574 (-1290 1260);
PAINT MONO (-1290 1260);
DISPLAY INVISIBLE (-1290 1260);
FORCEPROP 1 LASTPIN (-1300 1250) BN 11
J 0
(-1312 1258);
DISPLAY 0.680851 (-1312 1258);
PAINT GREEN (-1312 1258);
FORCEPROP 2 LAST CDS_LIB standard
J 0
(-1250 1250);
PAINT MONO (-1250 1250);
DISPLAY INVISIBLE (-1250 1250);
FORCEPROP 1 LAST BODY_TYPE PLUMBING
J 0
(-1250 1300);
DISPLAY 0.872340 (-1250 1300);
PAINT GREEN (-1250 1300);
DISPLAY INVISIBLE (-1250 1300);
FORCEPROP 1 LAST HDL_TAP TRUE
J 0
(-925 1125);
DISPLAY 0.872340 (-925 1125);
DISPLAY INVISIBLE (-925 1125);
FORCEPROP 1 LAST PATH I63
J 0
(-1252 1250);
DISPLAY 0.872340 (-1252 1250);
PAINT GREEN (-1252 1250);
DISPLAY INVISIBLE (-1252 1250);
FORCEADD TAP..1
(-1250 1300);
FORCEPROP 3 LASTPIN (-1300 1300) SIG_NAME M_C_CPU1_SB_DQ<12>
J 0
(-1290 1310);
DISPLAY 0.659574 (-1290 1310);
PAINT MONO (-1290 1310);
DISPLAY INVISIBLE (-1290 1310);
FORCEPROP 1 LASTPIN (-1300 1300) BN 12
J 0
(-1312 1308);
DISPLAY 0.680851 (-1312 1308);
PAINT GREEN (-1312 1308);
FORCEPROP 2 LAST CDS_LIB standard
J 0
(-1250 1300);
PAINT MONO (-1250 1300);
DISPLAY INVISIBLE (-1250 1300);
FORCEPROP 1 LAST BODY_TYPE PLUMBING
J 0
(-1250 1350);
DISPLAY 0.872340 (-1250 1350);
PAINT GREEN (-1250 1350);
DISPLAY INVISIBLE (-1250 1350);
FORCEPROP 1 LAST HDL_TAP TRUE
J 0
(-925 1175);
DISPLAY 0.872340 (-925 1175);
DISPLAY INVISIBLE (-925 1175);
FORCEPROP 1 LAST PATH I64
J 0
(-1252 1300);
DISPLAY 0.872340 (-1252 1300);
PAINT GREEN (-1252 1300);
DISPLAY INVISIBLE (-1252 1300);
FORCEADD TAP..1
(-1250 1350);
FORCEPROP 3 LASTPIN (-1300 1350) SIG_NAME M_C_CPU1_SB_DQ<13>
J 0
(-1290 1360);
DISPLAY 0.659574 (-1290 1360);
PAINT MONO (-1290 1360);
DISPLAY INVISIBLE (-1290 1360);
FORCEPROP 1 LASTPIN (-1300 1350) BN 13
J 0
(-1312 1358);
DISPLAY 0.680851 (-1312 1358);
PAINT GREEN (-1312 1358);
FORCEPROP 2 LAST CDS_LIB standard
J 0
(-1250 1350);
PAINT MONO (-1250 1350);
DISPLAY INVISIBLE (-1250 1350);
FORCEPROP 1 LAST BODY_TYPE PLUMBING
J 0
(-1250 1400);
DISPLAY 0.872340 (-1250 1400);
PAINT GREEN (-1250 1400);
DISPLAY INVISIBLE (-1250 1400);
FORCEPROP 1 LAST HDL_TAP TRUE
J 0
(-925 1225);
DISPLAY 0.872340 (-925 1225);
DISPLAY INVISIBLE (-925 1225);
FORCEPROP 1 LAST PATH I65
J 0
(-1252 1350);
DISPLAY 0.872340 (-1252 1350);
PAINT GREEN (-1252 1350);
DISPLAY INVISIBLE (-1252 1350);
FORCEADD TAP..1
(-1250 1400);
FORCEPROP 3 LASTPIN (-1300 1400) SIG_NAME M_C_CPU1_SB_DQ<14>
J 0
(-1290 1410);
DISPLAY 0.659574 (-1290 1410);
PAINT MONO (-1290 1410);
DISPLAY INVISIBLE (-1290 1410);
FORCEPROP 1 LASTPIN (-1300 1400) BN 14
J 0
(-1312 1408);
DISPLAY 0.680851 (-1312 1408);
PAINT GREEN (-1312 1408);
FORCEPROP 2 LAST CDS_LIB standard
J 0
(-1250 1400);
PAINT MONO (-1250 1400);
DISPLAY INVISIBLE (-1250 1400);
FORCEPROP 1 LAST BODY_TYPE PLUMBING
J 0
(-1250 1450);
DISPLAY 0.872340 (-1250 1450);
PAINT GREEN (-1250 1450);
DISPLAY INVISIBLE (-1250 1450);
FORCEPROP 1 LAST HDL_TAP TRUE
J 0
(-925 1275);
DISPLAY 0.872340 (-925 1275);
DISPLAY INVISIBLE (-925 1275);
FORCEPROP 1 LAST PATH I66
J 0
(-1252 1400);
DISPLAY 0.872340 (-1252 1400);
PAINT GREEN (-1252 1400);
DISPLAY INVISIBLE (-1252 1400);
FORCEADD TAP..1
(-1250 1450);
FORCEPROP 3 LASTPIN (-1300 1450) SIG_NAME M_C_CPU1_SB_DQ<15>
J 0
(-1290 1460);
DISPLAY 0.659574 (-1290 1460);
PAINT MONO (-1290 1460);
DISPLAY INVISIBLE (-1290 1460);
FORCEPROP 1 LASTPIN (-1300 1450) BN 15
J 0
(-1312 1458);
DISPLAY 0.680851 (-1312 1458);
PAINT GREEN (-1312 1458);
FORCEPROP 2 LAST CDS_LIB standard
J 0
(-1250 1450);
PAINT MONO (-1250 1450);
DISPLAY INVISIBLE (-1250 1450);
FORCEPROP 1 LAST BODY_TYPE PLUMBING
J 0
(-1250 1500);
DISPLAY 0.872340 (-1250 1500);
PAINT GREEN (-1250 1500);
DISPLAY INVISIBLE (-1250 1500);
FORCEPROP 1 LAST HDL_TAP TRUE
J 0
(-925 1325);
DISPLAY 0.872340 (-925 1325);
DISPLAY INVISIBLE (-925 1325);
FORCEPROP 1 LAST PATH I67
J 0
(-1252 1450);
DISPLAY 0.872340 (-1252 1450);
PAINT GREEN (-1252 1450);
DISPLAY INVISIBLE (-1252 1450);
FORCEADD TAP..1
(-1250 1550);
FORCEPROP 3 LASTPIN (-1300 1550) SIG_NAME M_C_CPU1_SB_DQ<17>
J 0
(-1290 1560);
DISPLAY 0.659574 (-1290 1560);
PAINT MONO (-1290 1560);
DISPLAY INVISIBLE (-1290 1560);
FORCEPROP 1 LASTPIN (-1300 1550) BN 17
J 0
(-1312 1558);
DISPLAY 0.680851 (-1312 1558);
PAINT GREEN (-1312 1558);
FORCEPROP 2 LAST CDS_LIB standard
J 0
(-1250 1550);
PAINT MONO (-1250 1550);
DISPLAY INVISIBLE (-1250 1550);
FORCEPROP 1 LAST BODY_TYPE PLUMBING
J 0
(-1250 1600);
DISPLAY 0.872340 (-1250 1600);
PAINT GREEN (-1250 1600);
DISPLAY INVISIBLE (-1250 1600);
FORCEPROP 1 LAST HDL_TAP TRUE
J 0
(-925 1425);
DISPLAY 0.872340 (-925 1425);
DISPLAY INVISIBLE (-925 1425);
FORCEPROP 1 LAST PATH I68
J 0
(-1252 1550);
DISPLAY 0.872340 (-1252 1550);
PAINT GREEN (-1252 1550);
DISPLAY INVISIBLE (-1252 1550);
FORCEADD TAP..1
(-1250 1500);
FORCEPROP 3 LASTPIN (-1300 1500) SIG_NAME M_C_CPU1_SB_DQ<16>
J 0
(-1290 1510);
DISPLAY 0.659574 (-1290 1510);
PAINT MONO (-1290 1510);
DISPLAY INVISIBLE (-1290 1510);
FORCEPROP 1 LASTPIN (-1300 1500) BN 16
J 0
(-1312 1508);
DISPLAY 0.680851 (-1312 1508);
PAINT GREEN (-1312 1508);
FORCEPROP 2 LAST CDS_LIB standard
J 0
(-1250 1500);
PAINT MONO (-1250 1500);
DISPLAY INVISIBLE (-1250 1500);
FORCEPROP 1 LAST BODY_TYPE PLUMBING
J 0
(-1250 1550);
DISPLAY 0.872340 (-1250 1550);
PAINT GREEN (-1250 1550);
DISPLAY INVISIBLE (-1250 1550);
FORCEPROP 1 LAST HDL_TAP TRUE
J 0
(-925 1375);
DISPLAY 0.872340 (-925 1375);
DISPLAY INVISIBLE (-925 1375);
FORCEPROP 1 LAST PATH I69
J 0
(-1252 1500);
DISPLAY 0.872340 (-1252 1500);
PAINT GREEN (-1252 1500);
DISPLAY INVISIBLE (-1252 1500);
FORCEADD TAP..1
(-1250 1600);
FORCEPROP 3 LASTPIN (-1300 1600) SIG_NAME M_C_CPU1_SB_DQ<18>
J 0
(-1290 1610);
DISPLAY 0.659574 (-1290 1610);
PAINT MONO (-1290 1610);
DISPLAY INVISIBLE (-1290 1610);
FORCEPROP 1 LASTPIN (-1300 1600) BN 18
J 0
(-1312 1608);
DISPLAY 0.680851 (-1312 1608);
PAINT GREEN (-1312 1608);
FORCEPROP 2 LAST CDS_LIB standard
J 0
(-1250 1600);
PAINT MONO (-1250 1600);
DISPLAY INVISIBLE (-1250 1600);
FORCEPROP 1 LAST BODY_TYPE PLUMBING
J 0
(-1250 1650);
DISPLAY 0.872340 (-1250 1650);
PAINT GREEN (-1250 1650);
DISPLAY INVISIBLE (-1250 1650);
FORCEPROP 1 LAST HDL_TAP TRUE
J 0
(-925 1475);
DISPLAY 0.872340 (-925 1475);
DISPLAY INVISIBLE (-925 1475);
FORCEPROP 1 LAST PATH I70
J 0
(-1252 1600);
DISPLAY 0.872340 (-1252 1600);
PAINT GREEN (-1252 1600);
DISPLAY INVISIBLE (-1252 1600);
FORCEADD TAP..1
(-1250 1650);
FORCEPROP 3 LASTPIN (-1300 1650) SIG_NAME M_C_CPU1_SB_DQ<19>
J 0
(-1290 1660);
DISPLAY 0.659574 (-1290 1660);
PAINT MONO (-1290 1660);
DISPLAY INVISIBLE (-1290 1660);
FORCEPROP 1 LASTPIN (-1300 1650) BN 19
J 0
(-1312 1658);
DISPLAY 0.680851 (-1312 1658);
PAINT GREEN (-1312 1658);
FORCEPROP 2 LAST CDS_LIB standard
J 0
(-1250 1650);
PAINT MONO (-1250 1650);
DISPLAY INVISIBLE (-1250 1650);
FORCEPROP 1 LAST BODY_TYPE PLUMBING
J 0
(-1250 1700);
DISPLAY 0.872340 (-1250 1700);
PAINT GREEN (-1250 1700);
DISPLAY INVISIBLE (-1250 1700);
FORCEPROP 1 LAST HDL_TAP TRUE
J 0
(-925 1525);
DISPLAY 0.872340 (-925 1525);
DISPLAY INVISIBLE (-925 1525);
FORCEPROP 1 LAST PATH I71
J 0
(-1252 1650);
DISPLAY 0.872340 (-1252 1650);
PAINT GREEN (-1252 1650);
DISPLAY INVISIBLE (-1252 1650);
FORCEADD TAP..1
(-1250 1700);
FORCEPROP 3 LASTPIN (-1300 1700) SIG_NAME M_C_CPU1_SB_DQ<20>
J 0
(-1290 1710);
DISPLAY 0.659574 (-1290 1710);
PAINT MONO (-1290 1710);
DISPLAY INVISIBLE (-1290 1710);
FORCEPROP 1 LASTPIN (-1300 1700) BN 20
J 0
(-1312 1708);
DISPLAY 0.680851 (-1312 1708);
PAINT GREEN (-1312 1708);
FORCEPROP 2 LAST CDS_LIB standard
J 0
(-1250 1700);
PAINT MONO (-1250 1700);
DISPLAY INVISIBLE (-1250 1700);
FORCEPROP 1 LAST BODY_TYPE PLUMBING
J 0
(-1250 1750);
DISPLAY 0.872340 (-1250 1750);
PAINT GREEN (-1250 1750);
DISPLAY INVISIBLE (-1250 1750);
FORCEPROP 1 LAST HDL_TAP TRUE
J 0
(-925 1575);
DISPLAY 0.872340 (-925 1575);
DISPLAY INVISIBLE (-925 1575);
FORCEPROP 1 LAST PATH I72
J 0
(-1252 1700);
DISPLAY 0.872340 (-1252 1700);
PAINT GREEN (-1252 1700);
DISPLAY INVISIBLE (-1252 1700);
FORCEADD TAP..1
(-1250 1750);
FORCEPROP 3 LASTPIN (-1300 1750) SIG_NAME M_C_CPU1_SB_DQ<21>
J 0
(-1290 1760);
DISPLAY 0.659574 (-1290 1760);
PAINT MONO (-1290 1760);
DISPLAY INVISIBLE (-1290 1760);
FORCEPROP 1 LASTPIN (-1300 1750) BN 21
J 0
(-1312 1758);
DISPLAY 0.680851 (-1312 1758);
PAINT GREEN (-1312 1758);
FORCEPROP 2 LAST CDS_LIB standard
J 0
(-1250 1750);
PAINT MONO (-1250 1750);
DISPLAY INVISIBLE (-1250 1750);
FORCEPROP 1 LAST BODY_TYPE PLUMBING
J 0
(-1250 1800);
DISPLAY 0.872340 (-1250 1800);
PAINT GREEN (-1250 1800);
DISPLAY INVISIBLE (-1250 1800);
FORCEPROP 1 LAST HDL_TAP TRUE
J 0
(-925 1625);
DISPLAY 0.872340 (-925 1625);
DISPLAY INVISIBLE (-925 1625);
FORCEPROP 1 LAST PATH I73
J 0
(-1252 1750);
DISPLAY 0.872340 (-1252 1750);
PAINT GREEN (-1252 1750);
DISPLAY INVISIBLE (-1252 1750);
FORCEADD TAP..1
(-1250 1800);
FORCEPROP 3 LASTPIN (-1300 1800) SIG_NAME M_C_CPU1_SB_DQ<22>
J 0
(-1290 1810);
DISPLAY 0.659574 (-1290 1810);
PAINT MONO (-1290 1810);
DISPLAY INVISIBLE (-1290 1810);
FORCEPROP 1 LASTPIN (-1300 1800) BN 22
J 0
(-1312 1808);
DISPLAY 0.680851 (-1312 1808);
PAINT GREEN (-1312 1808);
FORCEPROP 2 LAST CDS_LIB standard
J 0
(-1250 1800);
DISPLAY INVISIBLE (-1250 1800);
FORCEPROP 1 LAST BODY_TYPE PLUMBING
J 0
(-1250 1850);
DISPLAY 0.872340 (-1250 1850);
PAINT GREEN (-1250 1850);
DISPLAY INVISIBLE (-1250 1850);
FORCEPROP 1 LAST HDL_TAP TRUE
J 0
(-925 1675);
DISPLAY 0.872340 (-925 1675);
DISPLAY INVISIBLE (-925 1675);
FORCEPROP 1 LAST PATH I74
J 0
(-1252 1800);
DISPLAY 0.872340 (-1252 1800);
PAINT GREEN (-1252 1800);
DISPLAY INVISIBLE (-1252 1800);
FORCEADD TAP..1
(-1250 1850);
FORCEPROP 3 LASTPIN (-1300 1850) SIG_NAME M_C_CPU1_SB_DQ<23>
J 0
(-1290 1860);
DISPLAY 0.659574 (-1290 1860);
PAINT MONO (-1290 1860);
DISPLAY INVISIBLE (-1290 1860);
FORCEPROP 1 LASTPIN (-1300 1850) BN 23
J 0
(-1312 1858);
DISPLAY 0.680851 (-1312 1858);
PAINT GREEN (-1312 1858);
FORCEPROP 2 LAST CDS_LIB standard
J 0
(-1250 1850);
DISPLAY INVISIBLE (-1250 1850);
FORCEPROP 1 LAST BODY_TYPE PLUMBING
J 0
(-1250 1900);
DISPLAY 0.872340 (-1250 1900);
PAINT GREEN (-1250 1900);
DISPLAY INVISIBLE (-1250 1900);
FORCEPROP 1 LAST HDL_TAP TRUE
J 0
(-925 1725);
DISPLAY 0.872340 (-925 1725);
DISPLAY INVISIBLE (-925 1725);
FORCEPROP 1 LAST PATH I75
J 0
(-1252 1850);
DISPLAY 0.872340 (-1252 1850);
PAINT GREEN (-1252 1850);
DISPLAY INVISIBLE (-1252 1850);
FORCEADD TAP..1
(-1250 1900);
FORCEPROP 3 LASTPIN (-1300 1900) SIG_NAME M_C_CPU1_SB_DQ<24>
J 0
(-1290 1910);
DISPLAY 0.659574 (-1290 1910);
PAINT MONO (-1290 1910);
DISPLAY INVISIBLE (-1290 1910);
FORCEPROP 1 LASTPIN (-1300 1900) BN 24
J 0
(-1312 1908);
DISPLAY 0.680851 (-1312 1908);
PAINT GREEN (-1312 1908);
FORCEPROP 2 LAST CDS_LIB standard
J 0
(-1250 1900);
DISPLAY INVISIBLE (-1250 1900);
FORCEPROP 1 LAST BODY_TYPE PLUMBING
J 0
(-1250 1950);
DISPLAY 0.872340 (-1250 1950);
PAINT GREEN (-1250 1950);
DISPLAY INVISIBLE (-1250 1950);
FORCEPROP 1 LAST HDL_TAP TRUE
J 0
(-925 1775);
DISPLAY 0.872340 (-925 1775);
DISPLAY INVISIBLE (-925 1775);
FORCEPROP 1 LAST PATH I76
J 0
(-1252 1900);
DISPLAY 0.872340 (-1252 1900);
PAINT GREEN (-1252 1900);
DISPLAY INVISIBLE (-1252 1900);
FORCEADD TAP..1
(-1250 2000);
FORCEPROP 3 LASTPIN (-1300 2000) SIG_NAME M_C_CPU1_SB_DQ<26>
J 0
(-1290 2010);
DISPLAY 0.659574 (-1290 2010);
PAINT MONO (-1290 2010);
DISPLAY INVISIBLE (-1290 2010);
FORCEPROP 1 LASTPIN (-1300 2000) BN 26
J 0
(-1312 2008);
DISPLAY 0.680851 (-1312 2008);
PAINT GREEN (-1312 2008);
FORCEPROP 2 LAST CDS_LIB standard
J 0
(-1250 2000);
DISPLAY INVISIBLE (-1250 2000);
FORCEPROP 1 LAST BODY_TYPE PLUMBING
J 0
(-1250 2050);
DISPLAY 0.872340 (-1250 2050);
PAINT GREEN (-1250 2050);
DISPLAY INVISIBLE (-1250 2050);
FORCEPROP 1 LAST HDL_TAP TRUE
J 0
(-925 1875);
DISPLAY 0.872340 (-925 1875);
DISPLAY INVISIBLE (-925 1875);
FORCEPROP 1 LAST PATH I77
J 0
(-1252 2000);
DISPLAY 0.872340 (-1252 2000);
PAINT GREEN (-1252 2000);
DISPLAY INVISIBLE (-1252 2000);
FORCEADD TAP..1
(-1250 1950);
FORCEPROP 3 LASTPIN (-1300 1950) SIG_NAME M_C_CPU1_SB_DQ<25>
J 0
(-1290 1960);
DISPLAY 0.659574 (-1290 1960);
PAINT MONO (-1290 1960);
DISPLAY INVISIBLE (-1290 1960);
FORCEPROP 1 LASTPIN (-1300 1950) BN 25
J 0
(-1312 1958);
DISPLAY 0.680851 (-1312 1958);
PAINT GREEN (-1312 1958);
FORCEPROP 2 LAST CDS_LIB standard
J 0
(-1250 1950);
DISPLAY INVISIBLE (-1250 1950);
FORCEPROP 1 LAST BODY_TYPE PLUMBING
J 0
(-1250 2000);
DISPLAY 0.872340 (-1250 2000);
PAINT GREEN (-1250 2000);
DISPLAY INVISIBLE (-1250 2000);
FORCEPROP 1 LAST HDL_TAP TRUE
J 0
(-925 1825);
DISPLAY 0.872340 (-925 1825);
DISPLAY INVISIBLE (-925 1825);
FORCEPROP 1 LAST PATH I78
J 0
(-1252 1950);
DISPLAY 0.872340 (-1252 1950);
PAINT GREEN (-1252 1950);
DISPLAY INVISIBLE (-1252 1950);
FORCEADD TAP..1
(-1250 2050);
FORCEPROP 3 LASTPIN (-1300 2050) SIG_NAME M_C_CPU1_SB_DQ<27>
J 0
(-1290 2060);
DISPLAY 0.659574 (-1290 2060);
PAINT MONO (-1290 2060);
DISPLAY INVISIBLE (-1290 2060);
FORCEPROP 1 LASTPIN (-1300 2050) BN 27
J 0
(-1312 2058);
DISPLAY 0.680851 (-1312 2058);
PAINT GREEN (-1312 2058);
FORCEPROP 2 LAST CDS_LIB standard
J 0
(-1250 2050);
DISPLAY INVISIBLE (-1250 2050);
FORCEPROP 1 LAST BODY_TYPE PLUMBING
J 0
(-1250 2100);
DISPLAY 0.872340 (-1250 2100);
PAINT GREEN (-1250 2100);
DISPLAY INVISIBLE (-1250 2100);
FORCEPROP 1 LAST HDL_TAP TRUE
J 0
(-925 1925);
DISPLAY 0.872340 (-925 1925);
DISPLAY INVISIBLE (-925 1925);
FORCEPROP 1 LAST PATH I79
J 0
(-1252 2050);
DISPLAY 0.872340 (-1252 2050);
PAINT GREEN (-1252 2050);
DISPLAY INVISIBLE (-1252 2050);
FORCEADD OFFPAGE..1
(-3725 1350);
FORCEPROP 2 LAST $XR7 105 
J 0
(-4067 1386);
DISPLAY 0.638298 (-4067 1386);
PAINT MONO (-4067 1386);
FORCEPROP 2 LAST $XR6 104 
J 0
(-4217 1314);
DISPLAY 0.638298 (-4217 1314);
PAINT MONO (-4217 1314);
FORCEPROP 2 LAST $XR5 102 
J 0
(-4097 1314);
DISPLAY 0.638298 (-4097 1314);
PAINT MONO (-4097 1314);
FORCEPROP 2 LAST $XR4 101 
J 0
(-3977 1314);
DISPLAY 0.638298 (-3977 1314);
PAINT MONO (-3977 1314);
FORCEPROP 2 LAST $XR3 100 
J 0
(-4277 1350);
DISPLAY 0.638298 (-4277 1350);
PAINT MONO (-4277 1350);
FORCEPROP 2 LAST $XR2 99 
J 0
(-4157 1350);
DISPLAY 0.638298 (-4157 1350);
PAINT MONO (-4157 1350);
FORCEPROP 2 LAST $XR1 98 
J 0
(-4067 1350);
DISPLAY 0.638298 (-4067 1350);
PAINT MONO (-4067 1350);
FORCEPROP 2 LAST $XR0 230 
J 0
(-3977 1350);
DISPLAY 0.638298 (-3977 1350);
PAINT MONO (-3977 1350);
FORCEPROP 2 LAST CDS_LIB standard
J 0
(-3725 1350);
PAINT MONO (-3725 1350);
DISPLAY INVISIBLE (-3725 1350);
FORCEPROP 1 LAST OFFPAGE TRUE
J 0
(-3400 1225);
DISPLAY 0.872340 (-3400 1225);
DISPLAY INVISIBLE (-3400 1225);
FORCEPROP 1 LAST COMMENT_BODY TRUE
J 0
(-3600 1250);
DISPLAY 0.872340 (-3600 1250);
PAINT GREEN (-3600 1250);
DISPLAY INVISIBLE (-3600 1250);
FORCEPROP 2 LAST PATH I8
J 0
(-3675 1425);
DISPLAY 1.021277 (-3675 1425);
DISPLAY INVISIBLE (-3675 1425);
FORCEADD TAP..1
(-1250 2100);
FORCEPROP 3 LASTPIN (-1300 2100) SIG_NAME M_C_CPU1_SB_DQ<28>
J 0
(-1290 2110);
DISPLAY 0.659574 (-1290 2110);
PAINT MONO (-1290 2110);
DISPLAY INVISIBLE (-1290 2110);
FORCEPROP 1 LASTPIN (-1300 2100) BN 28
J 0
(-1312 2108);
DISPLAY 0.680851 (-1312 2108);
PAINT GREEN (-1312 2108);
FORCEPROP 2 LAST CDS_LIB standard
J 0
(-1250 2100);
DISPLAY INVISIBLE (-1250 2100);
FORCEPROP 1 LAST BODY_TYPE PLUMBING
J 0
(-1250 2150);
DISPLAY 0.872340 (-1250 2150);
PAINT GREEN (-1250 2150);
DISPLAY INVISIBLE (-1250 2150);
FORCEPROP 1 LAST HDL_TAP TRUE
J 0
(-925 1975);
DISPLAY 0.872340 (-925 1975);
DISPLAY INVISIBLE (-925 1975);
FORCEPROP 1 LAST PATH I80
J 0
(-1252 2100);
DISPLAY 0.872340 (-1252 2100);
PAINT GREEN (-1252 2100);
DISPLAY INVISIBLE (-1252 2100);
FORCEADD TAP..1
(-1250 2150);
FORCEPROP 3 LASTPIN (-1300 2150) SIG_NAME M_C_CPU1_SB_DQ<29>
J 0
(-1290 2160);
DISPLAY 0.659574 (-1290 2160);
PAINT MONO (-1290 2160);
DISPLAY INVISIBLE (-1290 2160);
FORCEPROP 1 LASTPIN (-1300 2150) BN 29
J 0
(-1312 2158);
DISPLAY 0.680851 (-1312 2158);
PAINT GREEN (-1312 2158);
FORCEPROP 2 LAST CDS_LIB standard
J 0
(-1250 2150);
DISPLAY INVISIBLE (-1250 2150);
FORCEPROP 1 LAST BODY_TYPE PLUMBING
J 0
(-1250 2200);
DISPLAY 0.872340 (-1250 2200);
PAINT GREEN (-1250 2200);
DISPLAY INVISIBLE (-1250 2200);
FORCEPROP 1 LAST HDL_TAP TRUE
J 0
(-925 2025);
DISPLAY 0.872340 (-925 2025);
DISPLAY INVISIBLE (-925 2025);
FORCEPROP 1 LAST PATH I81
J 0
(-1252 2150);
DISPLAY 0.872340 (-1252 2150);
PAINT GREEN (-1252 2150);
DISPLAY INVISIBLE (-1252 2150);
FORCEADD TAP..1
(-1250 2250);
FORCEPROP 3 LASTPIN (-1300 2250) SIG_NAME M_C_CPU1_SB_DQ<31>
J 0
(-1290 2260);
DISPLAY 0.659574 (-1290 2260);
PAINT MONO (-1290 2260);
DISPLAY INVISIBLE (-1290 2260);
FORCEPROP 1 LASTPIN (-1300 2250) BN 31
J 0
(-1312 2258);
DISPLAY 0.680851 (-1312 2258);
PAINT GREEN (-1312 2258);
FORCEPROP 2 LAST CDS_LIB standard
J 0
(-1250 2250);
DISPLAY INVISIBLE (-1250 2250);
FORCEPROP 1 LAST BODY_TYPE PLUMBING
J 0
(-1250 2300);
DISPLAY 0.872340 (-1250 2300);
PAINT GREEN (-1250 2300);
DISPLAY INVISIBLE (-1250 2300);
FORCEPROP 1 LAST HDL_TAP TRUE
J 0
(-925 2125);
DISPLAY 0.872340 (-925 2125);
DISPLAY INVISIBLE (-925 2125);
FORCEPROP 1 LAST PATH I82
J 0
(-1252 2250);
DISPLAY 0.872340 (-1252 2250);
PAINT GREEN (-1252 2250);
DISPLAY INVISIBLE (-1252 2250);
FORCEADD TAP..1
(-1250 2200);
FORCEPROP 3 LASTPIN (-1300 2200) SIG_NAME M_C_CPU1_SB_DQ<30>
J 0
(-1290 2210);
DISPLAY 0.659574 (-1290 2210);
PAINT MONO (-1290 2210);
DISPLAY INVISIBLE (-1290 2210);
FORCEPROP 1 LASTPIN (-1300 2200) BN 30
J 0
(-1312 2208);
DISPLAY 0.680851 (-1312 2208);
PAINT GREEN (-1312 2208);
FORCEPROP 2 LAST CDS_LIB standard
J 0
(-1250 2200);
DISPLAY INVISIBLE (-1250 2200);
FORCEPROP 1 LAST BODY_TYPE PLUMBING
J 0
(-1250 2250);
DISPLAY 0.872340 (-1250 2250);
PAINT GREEN (-1250 2250);
DISPLAY INVISIBLE (-1250 2250);
FORCEPROP 1 LAST HDL_TAP TRUE
J 0
(-925 2075);
DISPLAY 0.872340 (-925 2075);
DISPLAY INVISIBLE (-925 2075);
FORCEPROP 1 LAST PATH I83
J 0
(-1252 2200);
DISPLAY 0.872340 (-1252 2200);
PAINT GREEN (-1252 2200);
DISPLAY INVISIBLE (-1252 2200);
FORCEADD TAP..1
(-1250 2350);
FORCEPROP 3 LASTPIN (-1300 2350) SIG_NAME M_C_CPU1_SA_DQ<0>
J 0
(-1290 2360);
DISPLAY 0.659574 (-1290 2360);
PAINT MONO (-1290 2360);
DISPLAY INVISIBLE (-1290 2360);
FORCEPROP 1 LASTPIN (-1300 2350) BN 0
J 0
(-1312 2358);
DISPLAY 0.680851 (-1312 2358);
PAINT GREEN (-1312 2358);
FORCEPROP 2 LAST CDS_LIB standard
J 0
(-1250 2350);
PAINT MONO (-1250 2350);
DISPLAY INVISIBLE (-1250 2350);
FORCEPROP 1 LAST BODY_TYPE PLUMBING
J 0
(-1250 2400);
DISPLAY 0.872340 (-1250 2400);
PAINT GREEN (-1250 2400);
DISPLAY INVISIBLE (-1250 2400);
FORCEPROP 1 LAST HDL_TAP TRUE
J 0
(-925 2225);
DISPLAY 0.872340 (-925 2225);
DISPLAY INVISIBLE (-925 2225);
FORCEPROP 1 LAST PATH I84
J 0
(-1252 2350);
DISPLAY 0.872340 (-1252 2350);
PAINT GREEN (-1252 2350);
DISPLAY INVISIBLE (-1252 2350);
FORCEADD TAP..1
(-1250 2450);
FORCEPROP 3 LASTPIN (-1300 2450) SIG_NAME M_C_CPU1_SA_DQ<2>
J 0
(-1290 2460);
DISPLAY 0.659574 (-1290 2460);
PAINT MONO (-1290 2460);
DISPLAY INVISIBLE (-1290 2460);
FORCEPROP 1 LASTPIN (-1300 2450) BN 2
J 0
(-1312 2458);
DISPLAY 0.680851 (-1312 2458);
PAINT GREEN (-1312 2458);
FORCEPROP 2 LAST CDS_LIB standard
J 0
(-1250 2450);
PAINT MONO (-1250 2450);
DISPLAY INVISIBLE (-1250 2450);
FORCEPROP 1 LAST BODY_TYPE PLUMBING
J 0
(-1250 2500);
DISPLAY 0.872340 (-1250 2500);
PAINT GREEN (-1250 2500);
DISPLAY INVISIBLE (-1250 2500);
FORCEPROP 1 LAST HDL_TAP TRUE
J 0
(-925 2325);
DISPLAY 0.872340 (-925 2325);
DISPLAY INVISIBLE (-925 2325);
FORCEPROP 1 LAST PATH I85
J 0
(-1252 2450);
DISPLAY 0.872340 (-1252 2450);
PAINT GREEN (-1252 2450);
DISPLAY INVISIBLE (-1252 2450);
FORCEADD TAP..1
(-1250 2400);
FORCEPROP 3 LASTPIN (-1300 2400) SIG_NAME M_C_CPU1_SA_DQ<1>
J 0
(-1290 2410);
DISPLAY 0.659574 (-1290 2410);
PAINT MONO (-1290 2410);
DISPLAY INVISIBLE (-1290 2410);
FORCEPROP 1 LASTPIN (-1300 2400) BN 1
J 0
(-1312 2408);
DISPLAY 0.680851 (-1312 2408);
PAINT GREEN (-1312 2408);
FORCEPROP 2 LAST CDS_LIB standard
J 0
(-1250 2400);
PAINT MONO (-1250 2400);
DISPLAY INVISIBLE (-1250 2400);
FORCEPROP 1 LAST BODY_TYPE PLUMBING
J 0
(-1250 2450);
DISPLAY 0.872340 (-1250 2450);
PAINT GREEN (-1250 2450);
DISPLAY INVISIBLE (-1250 2450);
FORCEPROP 1 LAST HDL_TAP TRUE
J 0
(-925 2275);
DISPLAY 0.872340 (-925 2275);
DISPLAY INVISIBLE (-925 2275);
FORCEPROP 1 LAST PATH I86
J 0
(-1252 2400);
DISPLAY 0.872340 (-1252 2400);
PAINT GREEN (-1252 2400);
DISPLAY INVISIBLE (-1252 2400);
FORCEADD TAP..1
(-1250 2500);
FORCEPROP 3 LASTPIN (-1300 2500) SIG_NAME M_C_CPU1_SA_DQ<3>
J 0
(-1290 2510);
DISPLAY 0.659574 (-1290 2510);
PAINT MONO (-1290 2510);
DISPLAY INVISIBLE (-1290 2510);
FORCEPROP 1 LASTPIN (-1300 2500) BN 3
J 0
(-1312 2508);
DISPLAY 0.680851 (-1312 2508);
PAINT GREEN (-1312 2508);
FORCEPROP 2 LAST CDS_LIB standard
J 0
(-1250 2500);
PAINT MONO (-1250 2500);
DISPLAY INVISIBLE (-1250 2500);
FORCEPROP 1 LAST BODY_TYPE PLUMBING
J 0
(-1250 2550);
DISPLAY 0.872340 (-1250 2550);
PAINT GREEN (-1250 2550);
DISPLAY INVISIBLE (-1250 2550);
FORCEPROP 1 LAST HDL_TAP TRUE
J 0
(-925 2375);
DISPLAY 0.872340 (-925 2375);
DISPLAY INVISIBLE (-925 2375);
FORCEPROP 1 LAST PATH I87
J 0
(-1252 2500);
DISPLAY 0.872340 (-1252 2500);
PAINT GREEN (-1252 2500);
DISPLAY INVISIBLE (-1252 2500);
FORCEADD TAP..1
(-1250 2550);
FORCEPROP 3 LASTPIN (-1300 2550) SIG_NAME M_C_CPU1_SA_DQ<4>
J 0
(-1290 2560);
DISPLAY 0.659574 (-1290 2560);
PAINT MONO (-1290 2560);
DISPLAY INVISIBLE (-1290 2560);
FORCEPROP 1 LASTPIN (-1300 2550) BN 4
J 0
(-1312 2558);
DISPLAY 0.680851 (-1312 2558);
PAINT GREEN (-1312 2558);
FORCEPROP 2 LAST CDS_LIB standard
J 0
(-1250 2550);
PAINT MONO (-1250 2550);
DISPLAY INVISIBLE (-1250 2550);
FORCEPROP 1 LAST BODY_TYPE PLUMBING
J 0
(-1250 2600);
DISPLAY 0.872340 (-1250 2600);
PAINT GREEN (-1250 2600);
DISPLAY INVISIBLE (-1250 2600);
FORCEPROP 1 LAST HDL_TAP TRUE
J 0
(-925 2425);
DISPLAY 0.872340 (-925 2425);
DISPLAY INVISIBLE (-925 2425);
FORCEPROP 1 LAST PATH I88
J 0
(-1252 2550);
DISPLAY 0.872340 (-1252 2550);
PAINT GREEN (-1252 2550);
DISPLAY INVISIBLE (-1252 2550);
FORCEADD TAP..1
(-1250 2600);
FORCEPROP 3 LASTPIN (-1300 2600) SIG_NAME M_C_CPU1_SA_DQ<5>
J 0
(-1290 2610);
DISPLAY 0.659574 (-1290 2610);
PAINT MONO (-1290 2610);
DISPLAY INVISIBLE (-1290 2610);
FORCEPROP 1 LASTPIN (-1300 2600) BN 5
J 0
(-1312 2608);
DISPLAY 0.680851 (-1312 2608);
PAINT GREEN (-1312 2608);
FORCEPROP 2 LAST CDS_LIB standard
J 0
(-1250 2600);
PAINT MONO (-1250 2600);
DISPLAY INVISIBLE (-1250 2600);
FORCEPROP 1 LAST BODY_TYPE PLUMBING
J 0
(-1250 2650);
DISPLAY 0.872340 (-1250 2650);
PAINT GREEN (-1250 2650);
DISPLAY INVISIBLE (-1250 2650);
FORCEPROP 1 LAST HDL_TAP TRUE
J 0
(-925 2475);
DISPLAY 0.872340 (-925 2475);
DISPLAY INVISIBLE (-925 2475);
FORCEPROP 1 LAST PATH I89
J 0
(-1252 2600);
DISPLAY 0.872340 (-1252 2600);
PAINT GREEN (-1252 2600);
DISPLAY INVISIBLE (-1252 2600);
FORCEADD OFFPAGE..1
(-3725 1400);
FORCEPROP 2 LAST $XR0 103 
J 0
(-3977 1400);
DISPLAY 0.638298 (-3977 1400);
PAINT MONO (-3977 1400);
FORCEPROP 2 LAST CDS_LIB standard
J 0
(-3725 1400);
PAINT MONO (-3725 1400);
DISPLAY INVISIBLE (-3725 1400);
FORCEPROP 1 LAST OFFPAGE TRUE
J 0
(-3400 1275);
DISPLAY 0.872340 (-3400 1275);
DISPLAY INVISIBLE (-3400 1275);
FORCEPROP 1 LAST COMMENT_BODY TRUE
J 0
(-3600 1300);
DISPLAY 0.872340 (-3600 1300);
PAINT GREEN (-3600 1300);
DISPLAY INVISIBLE (-3600 1300);
FORCEPROP 2 LAST PATH I9
J 0
(-3675 1475);
DISPLAY 1.021277 (-3675 1475);
DISPLAY INVISIBLE (-3675 1475);
FORCEADD TAP..1
(-1250 2700);
FORCEPROP 3 LASTPIN (-1300 2700) SIG_NAME M_C_CPU1_SA_DQ<7>
J 0
(-1290 2710);
DISPLAY 0.659574 (-1290 2710);
PAINT MONO (-1290 2710);
DISPLAY INVISIBLE (-1290 2710);
FORCEPROP 1 LASTPIN (-1300 2700) BN 7
J 0
(-1312 2708);
DISPLAY 0.680851 (-1312 2708);
PAINT GREEN (-1312 2708);
FORCEPROP 2 LAST CDS_LIB standard
J 0
(-1250 2700);
PAINT MONO (-1250 2700);
DISPLAY INVISIBLE (-1250 2700);
FORCEPROP 1 LAST BODY_TYPE PLUMBING
J 0
(-1250 2750);
DISPLAY 0.872340 (-1250 2750);
PAINT GREEN (-1250 2750);
DISPLAY INVISIBLE (-1250 2750);
FORCEPROP 1 LAST HDL_TAP TRUE
J 0
(-925 2575);
DISPLAY 0.872340 (-925 2575);
DISPLAY INVISIBLE (-925 2575);
FORCEPROP 1 LAST PATH I90
J 0
(-1252 2700);
DISPLAY 0.872340 (-1252 2700);
PAINT GREEN (-1252 2700);
DISPLAY INVISIBLE (-1252 2700);
FORCEADD TAP..1
(-1250 2650);
FORCEPROP 3 LASTPIN (-1300 2650) SIG_NAME M_C_CPU1_SA_DQ<6>
J 0
(-1290 2660);
DISPLAY 0.659574 (-1290 2660);
PAINT MONO (-1290 2660);
DISPLAY INVISIBLE (-1290 2660);
FORCEPROP 1 LASTPIN (-1300 2650) BN 6
J 0
(-1312 2658);
DISPLAY 0.680851 (-1312 2658);
PAINT GREEN (-1312 2658);
FORCEPROP 2 LAST CDS_LIB standard
J 0
(-1250 2650);
PAINT MONO (-1250 2650);
DISPLAY INVISIBLE (-1250 2650);
FORCEPROP 1 LAST BODY_TYPE PLUMBING
J 0
(-1250 2700);
DISPLAY 0.872340 (-1250 2700);
PAINT GREEN (-1250 2700);
DISPLAY INVISIBLE (-1250 2700);
FORCEPROP 1 LAST HDL_TAP TRUE
J 0
(-925 2525);
DISPLAY 0.872340 (-925 2525);
DISPLAY INVISIBLE (-925 2525);
FORCEPROP 1 LAST PATH I91
J 0
(-1252 2650);
DISPLAY 0.872340 (-1252 2650);
PAINT GREEN (-1252 2650);
DISPLAY INVISIBLE (-1252 2650);
FORCEADD TAP..1
(-1250 2750);
FORCEPROP 3 LASTPIN (-1300 2750) SIG_NAME M_C_CPU1_SA_DQ<8>
J 0
(-1290 2760);
DISPLAY 0.659574 (-1290 2760);
PAINT MONO (-1290 2760);
DISPLAY INVISIBLE (-1290 2760);
FORCEPROP 1 LASTPIN (-1300 2750) BN 8
J 0
(-1312 2758);
DISPLAY 0.680851 (-1312 2758);
PAINT GREEN (-1312 2758);
FORCEPROP 2 LAST CDS_LIB standard
J 0
(-1250 2750);
PAINT MONO (-1250 2750);
DISPLAY INVISIBLE (-1250 2750);
FORCEPROP 1 LAST BODY_TYPE PLUMBING
J 0
(-1250 2800);
DISPLAY 0.872340 (-1250 2800);
PAINT GREEN (-1250 2800);
DISPLAY INVISIBLE (-1250 2800);
FORCEPROP 1 LAST HDL_TAP TRUE
J 0
(-925 2625);
DISPLAY 0.872340 (-925 2625);
DISPLAY INVISIBLE (-925 2625);
FORCEPROP 1 LAST PATH I92
J 0
(-1252 2750);
DISPLAY 0.872340 (-1252 2750);
PAINT GREEN (-1252 2750);
DISPLAY INVISIBLE (-1252 2750);
FORCEADD TAP..1
(-1250 2800);
FORCEPROP 3 LASTPIN (-1300 2800) SIG_NAME M_C_CPU1_SA_DQ<9>
J 0
(-1290 2810);
DISPLAY 0.659574 (-1290 2810);
PAINT MONO (-1290 2810);
DISPLAY INVISIBLE (-1290 2810);
FORCEPROP 1 LASTPIN (-1300 2800) BN 9
J 0
(-1312 2808);
DISPLAY 0.680851 (-1312 2808);
PAINT GREEN (-1312 2808);
FORCEPROP 2 LAST CDS_LIB standard
J 0
(-1250 2800);
PAINT MONO (-1250 2800);
DISPLAY INVISIBLE (-1250 2800);
FORCEPROP 1 LAST BODY_TYPE PLUMBING
J 0
(-1250 2850);
DISPLAY 0.872340 (-1250 2850);
PAINT GREEN (-1250 2850);
DISPLAY INVISIBLE (-1250 2850);
FORCEPROP 1 LAST HDL_TAP TRUE
J 0
(-925 2675);
DISPLAY 0.872340 (-925 2675);
DISPLAY INVISIBLE (-925 2675);
FORCEPROP 1 LAST PATH I93
J 0
(-1252 2800);
DISPLAY 0.872340 (-1252 2800);
PAINT GREEN (-1252 2800);
DISPLAY INVISIBLE (-1252 2800);
FORCEADD TAP..1
(-1250 2850);
FORCEPROP 3 LASTPIN (-1300 2850) SIG_NAME M_C_CPU1_SA_DQ<10>
J 0
(-1290 2860);
DISPLAY 0.659574 (-1290 2860);
PAINT MONO (-1290 2860);
DISPLAY INVISIBLE (-1290 2860);
FORCEPROP 1 LASTPIN (-1300 2850) BN 10
J 0
(-1312 2858);
DISPLAY 0.680851 (-1312 2858);
PAINT GREEN (-1312 2858);
FORCEPROP 2 LAST CDS_LIB standard
J 0
(-1250 2850);
PAINT MONO (-1250 2850);
DISPLAY INVISIBLE (-1250 2850);
FORCEPROP 1 LAST BODY_TYPE PLUMBING
J 0
(-1250 2900);
DISPLAY 0.872340 (-1250 2900);
PAINT GREEN (-1250 2900);
DISPLAY INVISIBLE (-1250 2900);
FORCEPROP 1 LAST HDL_TAP TRUE
J 0
(-925 2725);
DISPLAY 0.872340 (-925 2725);
DISPLAY INVISIBLE (-925 2725);
FORCEPROP 1 LAST PATH I94
J 0
(-1252 2850);
DISPLAY 0.872340 (-1252 2850);
PAINT GREEN (-1252 2850);
DISPLAY INVISIBLE (-1252 2850);
FORCEADD TAP..1
(-1250 2900);
FORCEPROP 3 LASTPIN (-1300 2900) SIG_NAME M_C_CPU1_SA_DQ<11>
J 0
(-1290 2910);
DISPLAY 0.659574 (-1290 2910);
PAINT MONO (-1290 2910);
DISPLAY INVISIBLE (-1290 2910);
FORCEPROP 1 LASTPIN (-1300 2900) BN 11
J 0
(-1312 2908);
DISPLAY 0.680851 (-1312 2908);
PAINT GREEN (-1312 2908);
FORCEPROP 2 LAST CDS_LIB standard
J 0
(-1250 2900);
PAINT MONO (-1250 2900);
DISPLAY INVISIBLE (-1250 2900);
FORCEPROP 1 LAST BODY_TYPE PLUMBING
J 0
(-1250 2950);
DISPLAY 0.872340 (-1250 2950);
PAINT GREEN (-1250 2950);
DISPLAY INVISIBLE (-1250 2950);
FORCEPROP 1 LAST HDL_TAP TRUE
J 0
(-925 2775);
DISPLAY 0.872340 (-925 2775);
DISPLAY INVISIBLE (-925 2775);
FORCEPROP 1 LAST PATH I95
J 0
(-1252 2900);
DISPLAY 0.872340 (-1252 2900);
PAINT GREEN (-1252 2900);
DISPLAY INVISIBLE (-1252 2900);
FORCEADD TAP..1
(-1250 2950);
FORCEPROP 3 LASTPIN (-1300 2950) SIG_NAME M_C_CPU1_SA_DQ<12>
J 0
(-1290 2960);
DISPLAY 0.659574 (-1290 2960);
PAINT MONO (-1290 2960);
DISPLAY INVISIBLE (-1290 2960);
FORCEPROP 1 LASTPIN (-1300 2950) BN 12
J 0
(-1312 2958);
DISPLAY 0.680851 (-1312 2958);
PAINT GREEN (-1312 2958);
FORCEPROP 2 LAST CDS_LIB standard
J 0
(-1250 2950);
PAINT MONO (-1250 2950);
DISPLAY INVISIBLE (-1250 2950);
FORCEPROP 1 LAST BODY_TYPE PLUMBING
J 0
(-1250 3000);
DISPLAY 0.872340 (-1250 3000);
PAINT GREEN (-1250 3000);
DISPLAY INVISIBLE (-1250 3000);
FORCEPROP 1 LAST HDL_TAP TRUE
J 0
(-925 2825);
DISPLAY 0.872340 (-925 2825);
DISPLAY INVISIBLE (-925 2825);
FORCEPROP 1 LAST PATH I96
J 0
(-1252 2950);
DISPLAY 0.872340 (-1252 2950);
PAINT GREEN (-1252 2950);
DISPLAY INVISIBLE (-1252 2950);
FORCEADD TAP..1
(-1250 3000);
FORCEPROP 3 LASTPIN (-1300 3000) SIG_NAME M_C_CPU1_SA_DQ<13>
J 0
(-1290 3010);
DISPLAY 0.659574 (-1290 3010);
PAINT MONO (-1290 3010);
DISPLAY INVISIBLE (-1290 3010);
FORCEPROP 1 LASTPIN (-1300 3000) BN 13
J 0
(-1312 3008);
DISPLAY 0.680851 (-1312 3008);
PAINT GREEN (-1312 3008);
FORCEPROP 2 LAST CDS_LIB standard
J 0
(-1250 3000);
PAINT MONO (-1250 3000);
DISPLAY INVISIBLE (-1250 3000);
FORCEPROP 1 LAST BODY_TYPE PLUMBING
J 0
(-1250 3050);
DISPLAY 0.872340 (-1250 3050);
PAINT GREEN (-1250 3050);
DISPLAY INVISIBLE (-1250 3050);
FORCEPROP 1 LAST HDL_TAP TRUE
J 0
(-925 2875);
DISPLAY 0.872340 (-925 2875);
DISPLAY INVISIBLE (-925 2875);
FORCEPROP 1 LAST PATH I97
J 0
(-1252 3000);
DISPLAY 0.872340 (-1252 3000);
PAINT GREEN (-1252 3000);
DISPLAY INVISIBLE (-1252 3000);
FORCEADD TAP..1
(-1250 3050);
FORCEPROP 3 LASTPIN (-1300 3050) SIG_NAME M_C_CPU1_SA_DQ<14>
J 0
(-1290 3060);
DISPLAY 0.659574 (-1290 3060);
PAINT MONO (-1290 3060);
DISPLAY INVISIBLE (-1290 3060);
FORCEPROP 1 LASTPIN (-1300 3050) BN 14
J 0
(-1312 3058);
DISPLAY 0.680851 (-1312 3058);
PAINT GREEN (-1312 3058);
FORCEPROP 2 LAST CDS_LIB standard
J 0
(-1250 3050);
PAINT MONO (-1250 3050);
DISPLAY INVISIBLE (-1250 3050);
FORCEPROP 1 LAST BODY_TYPE PLUMBING
J 0
(-1250 3100);
DISPLAY 0.872340 (-1250 3100);
PAINT GREEN (-1250 3100);
DISPLAY INVISIBLE (-1250 3100);
FORCEPROP 1 LAST HDL_TAP TRUE
J 0
(-925 2925);
DISPLAY 0.872340 (-925 2925);
DISPLAY INVISIBLE (-925 2925);
FORCEPROP 1 LAST PATH I98
J 0
(-1252 3050);
DISPLAY 0.872340 (-1252 3050);
PAINT GREEN (-1252 3050);
DISPLAY INVISIBLE (-1252 3050);
FORCEADD TAP..1
(-1250 3150);
FORCEPROP 3 LASTPIN (-1300 3150) SIG_NAME M_C_CPU1_SA_DQ<16>
J 0
(-1290 3160);
DISPLAY 0.659574 (-1290 3160);
PAINT MONO (-1290 3160);
DISPLAY INVISIBLE (-1290 3160);
FORCEPROP 1 LASTPIN (-1300 3150) BN 16
J 0
(-1312 3158);
DISPLAY 0.680851 (-1312 3158);
PAINT GREEN (-1312 3158);
FORCEPROP 2 LAST CDS_LIB standard
J 0
(-1250 3150);
PAINT MONO (-1250 3150);
DISPLAY INVISIBLE (-1250 3150);
FORCEPROP 1 LAST BODY_TYPE PLUMBING
J 0
(-1250 3200);
DISPLAY 0.872340 (-1250 3200);
PAINT GREEN (-1250 3200);
DISPLAY INVISIBLE (-1250 3200);
FORCEPROP 1 LAST HDL_TAP TRUE
J 0
(-925 3025);
DISPLAY 0.872340 (-925 3025);
DISPLAY INVISIBLE (-925 3025);
FORCEPROP 1 LAST PATH I99
J 0
(-1252 3150);
DISPLAY 0.872340 (-1252 3150);
PAINT GREEN (-1252 3150);
DISPLAY INVISIBLE (-1252 3150);
FORCEADD CAD_NOTE..1
(600 -550);
FORCEPROP 0 LAST S1 PLACE THE BYPASS CAPS CLOSE TO DIMM
J 0
(475 -675);
DISPLAY 1.021277 (475 -675);
PAINT WHITE (475 -675);
FORCEPROP 2 LAST CDS_LIB logical_power
J 0
(600 -550);
PAINT MONO (600 -550);
DISPLAY INVISIBLE (600 -550);
FORCEPROP 1 LAST COMMENT_BODY TRUE
J 0
(625 -450);
DISPLAY 0.978723 (625 -450);
DISPLAY INVISIBLE (625 -450);
FORCEADD QUANTA_TITLE_BLOCK_C..1
(5075 -1850);
FORCEPROP 0 LAST CDS_CON_LAST_MODIFIED Fri Aug 25 14:01:23 2023
J 0
(3190 -1835);
PAINT MONO (3190 -1835);
DISPLAY INVISIBLE (3190 -1835);
FORCEPROP 1 LAST CUSTOM_TXT_CDS <CON_LAST_MODIFIED>
J 0
(3190 -1835);
DISPLAY 0.978723 (3190 -1835);
FORCEPROP 2 LAST CUSTOM_TXT_CDS <XR_PAGE_TITLE>
J 0
(-2815 3400);
DISPLAY 0.638298 (-2815 3400);
PAINT PINK (-2815 3400);
DISPLAY INVISIBLE (-2815 3400);
FORCEPROP 2 LAST CUSTOM_TXT_CDS <Q_NUMBER>
J 0
(3672 -1747);
DISPLAY 1.212766 (3672 -1747);
FORCEPROP 1 LAST CUSTOM_TXT_CDS <NAME_2>
J 0
(1900 -1800);
FORCEPROP 1 LAST CUSTOM_TXT_CDS <NAME_1>
J 0
(1900 -1675);
FORCEPROP 1 LAST CUSTOM_TXT_CDS <Q_PROJ>
J 0
(2693 -1748);
DISPLAY 1.212766 (2693 -1748);
FORCEPROP 1 LAST CUSTOM_TXT_CDS <Q_REV>
J 0
(4891 -1747);
DISPLAY 1.212766 (4891 -1747);
FORCEPROP 1 LAST CUSTOM_TXT_CDS <CON_PAGE_NUM> OF <CON_TOTAL_PAGES>
J 0
(4629 -1832);
DISPLAY 0.978723 (4629 -1832);
FORCEPROP 1 LAST Q_TITLE DDR5 - CPU1 CHC DIMM2(BLACK)
J 0
(-4291 -1824);
DISPLAY 2.446809 (-4291 -1824);
PAINT GREEN (-4291 -1824);
FORCEPROP 1 LAST Q_DEPT 
J 1
(1312 -1801);
DISPLAY 1.957447 (1312 -1801);
PAINT GREEN (1312 -1801);
FORCEPROP 2 LAST CDS_XR_PAGE_TITLE CR-103 : @S9S_MB_2U_LIB.S9S_MB_2U(SCH_1):PAGE103
J 0
(-2815 3400);
DISPLAY 0.638298 (-2815 3400);
PAINT PINK (-2815 3400);
DISPLAY INVISIBLE (-2815 3400);
FORCEPROP 1 LAST COMMENT_BODY TRUE
J 0
(5087 -1863);
DISPLAY 0.978723 (5087 -1863);
PAINT GREEN (5087 -1863);
DISPLAY INVISIBLE (5087 -1863);
FORCEPROP 2 LAST CDS_LIB pure_quanta
J 0
(5075 -1850);
PAINT MONO (5075 -1850);
DISPLAY INVISIBLE (5075 -1850);
FORCEPROP 1 LAST CDS_LMAN_SYM_OUTLINE -9475,6775,100,-125
J 0
(5075 -1850);
DISPLAY 0.468085 (5075 -1850);
PAINT GREEN (5075 -1850);
DISPLAY INVISIBLE (5075 -1850);
FORCEPROP 2 LAST PAGE_BORDER TRUE
J 0
(-2815 3400);
DISPLAY 0.638298 (-2815 3400);
PAINT PINK (-2815 3400);
DISPLAY INVISIBLE (-2815 3400);
WIRE 17 -1 (-1200 3925)(-475 3925);
FORCEPROP 2 LAST SIG_NAME M_C_CPU1_SA_DQ<31:0>
J 0
(-1135 3935);
DISPLAY 0.680851 (-1135 3935);
PAINT WHITE (-1135 3935);
WIRE 17 -1 (-3775 2525)(-2950 2525);
FORCEPROP 2 LAST SIG_NAME M_C_CPU1_SA_CB<7:0>
J 0
(-3685 2535);
DISPLAY 0.680851 (-3685 2535);
PAINT WHITE (-3685 2535);
WIRE 17 -1 (-2950 2375)(-2950 2425);
WIRE 17 -1 (-2950 2325)(-2950 2375);
WIRE 17 -1 (-2950 2425)(-2950 2475);
WIRE 17 -1 (-2950 2475)(-2950 2525);
WIRE 17 -1 (-2950 2275)(-2950 2325);
WIRE 17 -1 (-2950 2225)(-2950 2275);
WIRE 17 -1 (-2950 2175)(-2950 2225);
WIRE 17 -1 (-3775 2075)(-2950 2075);
FORCEPROP 2 LAST SIG_NAME M_C_CPU1_SB_CB<7:0>
J 0
(-3685 2085);
DISPLAY 0.680851 (-3685 2085);
PAINT WHITE (-3685 2085);
WIRE 17 -1 (-2950 3625)(-2950 3675);
WIRE 17 -1 (-2950 3675)(-2950 3725);
WIRE 17 -1 (-2950 3725)(-2950 3775);
WIRE 17 -1 (-2950 3775)(-2950 3825);
WIRE 17 -1 (-2950 3825)(-2950 3875);
WIRE 17 -1 (-2950 3875)(-2950 3925);
WIRE 17 -1 (-3775 3925)(-2950 3925);
FORCEPROP 2 LAST SIG_NAME M_C_CPU1_SA_CA<6:0>
J 0
(-3685 3935);
DISPLAY 0.680851 (-3685 3935);
PAINT WHITE (-3685 3935);
WIRE 17 -1 (-2950 3225)(-2950 3275);
WIRE 17 -1 (-2950 3275)(-2950 3325);
WIRE 17 -1 (-2950 3325)(-2950 3375);
WIRE 17 -1 (-2950 3375)(-2950 3425);
WIRE 17 -1 (-2950 3425)(-2950 3475);
WIRE 17 -1 (-2950 3475)(-2950 3525);
WIRE 17 -1 (-3775 3525)(-2950 3525);
FORCEPROP 2 LAST SIG_NAME M_C_CPU1_SB_CA<6:0>
J 0
(-3685 3535);
DISPLAY 0.680851 (-3685 3535);
PAINT WHITE (-3685 3535);
WIRE 17 -1 (-2950 2025)(-2950 2075);
WIRE 17 -1 (-2950 1975)(-2950 2025);
WIRE 17 -1 (-2950 1925)(-2950 1975);
WIRE 17 -1 (-2950 1875)(-2950 1925);
WIRE 17 -1 (-2950 1825)(-2950 1875);
WIRE 17 -1 (-2950 1775)(-2950 1825);
WIRE 17 -1 (-2950 1725)(-2950 1775);
WIRE 17 -1 (-1200 3875)(-1200 3925);
WIRE 17 -1 (-1200 3825)(-1200 3875);
WIRE 17 -1 (-1200 3775)(-1200 3825);
WIRE 17 -1 (-1200 3725)(-1200 3775);
WIRE 17 -1 (-1200 3675)(-1200 3725);
WIRE 17 -1 (-1200 3625)(-1200 3675);
WIRE 17 -1 (-1200 3575)(-1200 3625);
WIRE 17 -1 (-1200 3525)(-1200 3575);
WIRE 17 -1 (-1200 3475)(-1200 3525);
WIRE 17 -1 (-1200 3425)(-1200 3475);
WIRE 17 -1 (-1200 3375)(-1200 3425);
WIRE 17 -1 (-1200 3325)(-1200 3375);
WIRE 17 -1 (-1200 3275)(-1200 3325);
WIRE 17 -1 (-1200 3225)(-1200 3275);
WIRE 17 -1 (-1200 3175)(-1200 3225);
WIRE 17 -1 (-1200 3125)(-1200 3175);
WIRE 17 -1 (-1200 3075)(-1200 3125);
WIRE 17 -1 (-1200 3025)(-1200 3075);
WIRE 17 -1 (-1200 2975)(-1200 3025);
WIRE 17 -1 (-1200 2925)(-1200 2975);
WIRE 17 -1 (-1200 2875)(-1200 2925);
WIRE 17 -1 (-1200 2825)(-1200 2875);
WIRE 17 -1 (-1200 2775)(-1200 2825);
WIRE 17 -1 (-1200 2725)(-1200 2775);
WIRE 17 -1 (-1200 2675)(-1200 2725);
WIRE 17 -1 (-1200 2625)(-1200 2675);
WIRE 17 -1 (-1200 2575)(-1200 2625);
WIRE 17 -1 (-1200 2525)(-1200 2575);
WIRE 17 -1 (-1200 2475)(-1200 2525);
WIRE 17 -1 (-1200 2425)(-1200 2475);
WIRE 17 -1 (-1200 2375)(-1200 2425);
WIRE 17 -1 (-1200 2125)(-1200 2175);
WIRE 17 -1 (-1200 2075)(-1200 2125);
WIRE 17 -1 (-1200 2175)(-1200 2225);
WIRE 17 -1 (-1200 2225)(-1200 2275);
WIRE 17 -1 (-1200 2025)(-1200 2075);
WIRE 17 -1 (-1200 1975)(-1200 2025);
WIRE 17 -1 (-1200 2275)(-475 2275);
FORCEPROP 2 LAST SIG_NAME M_C_CPU1_SB_DQ<31:0>
J 0
(-1135 2285);
DISPLAY 0.680851 (-1135 2285);
PAINT WHITE (-1135 2285);
WIRE 17 -1 (-1200 1925)(-1200 1975);
WIRE 17 -1 (-1200 1875)(-1200 1925);
WIRE 17 -1 (-1200 1825)(-1200 1875);
WIRE 17 -1 (-1200 1775)(-1200 1825);
WIRE 17 -1 (-1200 1725)(-1200 1775);
WIRE 17 -1 (-1200 1675)(-1200 1725);
WIRE 17 -1 (-1200 1625)(-1200 1675);
WIRE 17 -1 (-1200 1575)(-1200 1625);
WIRE 17 -1 (-1200 1525)(-1200 1575);
WIRE 17 -1 (-1200 1475)(-1200 1525);
WIRE 17 -1 (-1200 1425)(-1200 1475);
WIRE 17 -1 (-1200 1375)(-1200 1425);
WIRE 17 -1 (-1200 1325)(-1200 1375);
WIRE 17 -1 (-1200 1275)(-1200 1325);
WIRE 17 -1 (-1200 1225)(-1200 1275);
WIRE 17 -1 (-1200 1175)(-1200 1225);
WIRE 17 -1 (-1200 1125)(-1200 1175);
WIRE 17 -1 (-1200 1075)(-1200 1125);
WIRE 17 -1 (-1200 1025)(-1200 1075);
WIRE 17 -1 (-1200 975)(-1200 1025);
WIRE 17 -1 (-1200 925)(-1200 975);
WIRE 17 -1 (-1200 875)(-1200 925);
WIRE 17 -1 (-1200 825)(-1200 875);
WIRE 17 -1 (-1200 775)(-1200 825);
WIRE 17 -1 (-1200 725)(-1200 775);
WIRE 17 -1 (1550 1975)(1550 2075);
WIRE 17 -1 (1550 2075)(1550 2175);
WIRE 17 -1 (1550 2175)(1550 2275);
WIRE 17 -1 (1550 2375)(1550 2275);
WIRE 17 -1 (1550 2375)(1550 2475);
WIRE 17 -1 (1550 2475)(1550 2575);
WIRE 17 -1 (1550 2575)(1550 2675);
WIRE 17 -1 (1550 2675)(1550 2775);
WIRE 17 -1 (1550 2775)(1550 2875);
WIRE 17 -1 (1550 2875)(2575 2875);
FORCEPROP 2 LAST SIG_NAME M_C_CPU1_SB_DQS_DP<9:0>
J 0
(1790 2885);
DISPLAY 0.680851 (1790 2885);
PAINT WHITE (1790 2885);
WIRE 17 -1 (1550 3025)(1550 3125);
WIRE 17 -1 (1550 3125)(1550 3225);
WIRE 17 -1 (1550 3225)(1550 3325);
WIRE 17 -1 (1550 3425)(1550 3325);
WIRE 17 -1 (1550 3425)(1550 3525);
WIRE 17 -1 (1550 3525)(1550 3625);
WIRE 17 -1 (1550 3625)(1550 3725);
WIRE 17 -1 (1550 3725)(1550 3825);
WIRE 17 -1 (1550 3825)(1550 3925);
WIRE 17 -1 (1550 3925)(2575 3925);
FORCEPROP 2 LAST SIG_NAME M_C_CPU1_SA_DQS_DP<9:0>
J 0
(1790 3935);
DISPLAY 0.680851 (1790 3935);
PAINT WHITE (1790 3935);
WIRE 17 -1 (1725 1925)(1725 2025);
WIRE 17 -1 (1725 2025)(1725 2125);
WIRE 17 -1 (1725 2125)(1725 2225);
WIRE 17 -1 (1725 2325)(1725 2225);
WIRE 17 -1 (1725 2325)(1725 2425);
WIRE 17 -1 (1725 2425)(1725 2525);
WIRE 17 -1 (1725 2525)(1725 2625);
WIRE 17 -1 (1725 2625)(1725 2725);
WIRE 17 -1 (1725 2725)(1725 2825);
WIRE 17 -1 (1725 2825)(2575 2825);
FORCEPROP 2 LAST SIG_NAME M_C_CPU1_SB_DQS_DN<9:0>
J 0
(1790 2835);
DISPLAY 0.680851 (1790 2835);
PAINT WHITE (1790 2835);
WIRE 17 -1 (1725 3075)(1725 3175);
WIRE 17 -1 (1725 2975)(1725 3075);
WIRE 17 -1 (1725 3175)(1725 3275);
WIRE 17 -1 (1725 3375)(1725 3275);
WIRE 17 -1 (1725 3375)(1725 3475);
WIRE 17 -1 (1725 3475)(1725 3575);
WIRE 17 -1 (1725 3575)(1725 3675);
WIRE 17 -1 (1725 3675)(1725 3775);
WIRE 17 -1 (1725 3775)(1725 3875);
WIRE 17 -1 (1725 3875)(2575 3875);
FORCEPROP 2 LAST SIG_NAME M_C_CPU1_SA_DQS_DN<9:0>
J 0
(1790 3885);
DISPLAY 0.680851 (1790 3885);
PAINT WHITE (1790 3885);
WIRE 16 -1 (475 125)(475 300);
WIRE 16 -1 (1475 300)(1475 250);
WIRE 16 -1 (3175 4400)(3175 3900);
WIRE 16 -1 (-3725 1725)(-3725 1450);
WIRE 16 -1 (-2675 -425)(-2675 -350);
WIRE 16 -1 (475 -75)(475 -300);
WIRE 16 -1 (2100 -300)(2100 -225);
WIRE 16 -1 (3175 250)(3175 650);
WIRE 16 -1 (4875 550)(4875 250);
WIRE 16 -1 (4875 600)(4875 550);
WIRE 16 -1 (4625 550)(4875 550);
WIRE 16 3135 (125 525)(125 -775);
WIRE 16 3135 (2725 525)(125 525);
WIRE 16 3135 (125 -775)(2725 -775);
WIRE 16 3135 (2725 -775)(2725 525);
WIRE 16 -1 (-1475 900)(-1300 900);
WIRE 16 -1 (-2675 1550)(-3775 1550);
FORCEPROP 2 LAST SIG_NAME M_C_CPU1_ALERT_N
J 0
(-3687 1559);
DISPLAY 0.680851 (-3687 1559);
PAINT WHITE (-3687 1559);
WIRE 16 -1 (-2675 1350)(-3675 1350);
FORCEPROP 2 LAST SIG_NAME I3C_SPD_DDRABCD_CPU1_LVC1_SDA
J 0
(-3685 1360);
DISPLAY 0.680851 (-3685 1360);
PAINT WHITE (-3685 1360);
WIRE 16 -1 (-3725 1450)(-2675 1450);
WIRE 16 -1 (-2675 1400)(-3675 1400);
FORCEPROP 2 LAST SIG_NAME PD_CHC_CPU1_DIMM2_SAA
J 0
(-3685 1410);
DISPLAY 0.680851 (-3685 1410);
PAINT WHITE (-3685 1410);
WIRE 16 -1 (-3100 1600)(-2675 1600);
WIRE 16 -1 (-3100 1650)(-3775 1650);
FORCEPROP 2 LAST SIG_NAME RST_M_CD_CPU1_FPGA_N
J 0
(-3687 1659);
DISPLAY 0.680851 (-3687 1659);
PAINT WHITE (-3687 1659);
WIRE 16 -1 (-3100 1650)(-3100 1600);
WIRE 16 -1 (-2850 1700)(-2675 1700);
WIRE 16 -1 (-4150 1200)(-3950 1200);
WIRE 16 -1 (-4150 1200)(-4150 1300);
WIRE 16 -1 (-2675 1300)(-4150 1300);
FORCEPROP 2 LAST SIG_NAME I3C_SPD_DDRABCD_CPU1_LVC1_SCL_R6
J 0
(-3735 1310);
DISPLAY 0.680851 (-3735 1310);
PAINT WHITE (-3735 1310);
WIRE 16 -1 (-2550 1125)(-2600 1125);
WIRE 16 -1 (-3750 1200)(-2550 1200);
FORCEPROP 2 LAST SIG_NAME I3C_SPD_DDRABCD_CPU1_LVC1_SCL
J 0
(-3585 1210);
DISPLAY 0.680851 (-3585 1210);
PAINT WHITE (-3585 1210);
WIRE 16 -1 (-2550 1200)(-2550 1125);
WIRE 16 -1 (-2675 1050)(-3775 1050);
FORCEPROP 2 LAST SIG_NAME PWRGD_CHC_CPU1_DIMM2
J 0
(-3687 1059);
DISPLAY 0.680851 (-3687 1059);
PAINT WHITE (-3687 1059);
WIRE 16 -1 (-2675 950)(-3775 950);
FORCEPROP 2 LAST SIG_NAME TP_CHC_CPU1_DIMM2_FRU_6
J 0
(-3687 959);
DISPLAY 0.680851 (-3687 959);
PAINT WHITE (-3687 959);
WIRE 16 -1 (-2850 1900)(-2675 1900);
WIRE 16 -1 (-2675 2750)(-3775 2750);
FORCEPROP 2 LAST SIG_NAME M_C_CPU1_SB_CS_N<2>
J 0
(-3687 2759);
DISPLAY 0.680851 (-3687 2759);
PAINT WHITE (-3687 2759);
WIRE 16 -1 (-2675 2800)(-3775 2800);
FORCEPROP 2 LAST SIG_NAME M_C_CPU1_SB_CS_N<3>
J 0
(-3687 2809);
DISPLAY 0.680851 (-3687 2809);
PAINT WHITE (-3687 2809);
WIRE 16 -1 (-2675 2900)(-3775 2900);
FORCEPROP 2 LAST SIG_NAME M_C_CPU1_SA_CS_N<2>
J 0
(-3687 2909);
DISPLAY 0.680851 (-3687 2909);
PAINT WHITE (-3687 2909);
WIRE 16 -1 (1350 2450)(1450 2450);
WIRE 16 -1 (1350 2400)(1625 2400);
WIRE 16 -1 (1350 3850)(1625 3850);
WIRE 16 -1 (1350 3750)(1625 3750);
WIRE 16 -1 (1350 3650)(1625 3650);
WIRE 16 -1 (1350 3550)(1625 3550);
WIRE 16 -1 (1350 3350)(1625 3350);
WIRE 16 -1 (1350 3450)(1625 3450);
WIRE 16 -1 (1350 3250)(1625 3250);
WIRE 16 -1 (1350 3150)(1625 3150);
WIRE 16 -1 (1350 2950)(1625 2950);
WIRE 16 -1 (1350 3050)(1625 3050);
WIRE 16 -1 (1350 2700)(1625 2700);
WIRE 16 -1 (1350 2800)(1625 2800);
WIRE 16 -1 (1350 2600)(1625 2600);
WIRE 16 -1 (1350 2500)(1625 2500);
WIRE 16 -1 (1350 2200)(1625 2200);
WIRE 16 -1 (1350 2300)(1625 2300);
WIRE 16 -1 (1350 2100)(1625 2100);
WIRE 16 -1 (1350 2000)(1625 2000);
WIRE 16 -1 (1350 1900)(1625 1900);
WIRE 16 -1 (1350 3900)(1450 3900);
WIRE 16 -1 (1350 3800)(1450 3800);
WIRE 16 -1 (1350 3700)(1450 3700);
WIRE 16 -1 (1350 3600)(1450 3600);
WIRE 16 -1 (1350 3500)(1450 3500);
WIRE 16 -1 (1350 3400)(1450 3400);
WIRE 16 -1 (1350 3300)(1450 3300);
WIRE 16 -1 (1350 3200)(1450 3200);
WIRE 16 -1 (1350 3100)(1450 3100);
WIRE 16 -1 (1350 3000)(1450 3000);
WIRE 16 -1 (1350 2850)(1450 2850);
WIRE 16 -1 (1350 2750)(1450 2750);
WIRE 16 -1 (1350 2650)(1450 2650);
WIRE 16 -1 (1350 2550)(1450 2550);
WIRE 16 -1 (1350 2350)(1450 2350);
WIRE 16 -1 (1350 2250)(1450 2250);
WIRE 16 -1 (1350 2150)(1450 2150);
WIRE 16 -1 (1350 2050)(1450 2050);
WIRE 16 -1 (1350 1950)(1450 1950);
WIRE 16 -1 (-1475 1200)(-1300 1200);
WIRE 16 -1 (-1475 1600)(-1300 1600);
WIRE 16 -1 (-1475 3750)(-1300 3750);
WIRE 16 -1 (3425 3800)(3175 3800);
WIRE 16 -1 (3175 3850)(3175 3800);
WIRE 16 -1 (3175 3850)(3425 3850);
WIRE 16 -1 (3175 3900)(3175 3850);
WIRE 16 -1 (3425 3900)(3175 3900);
WIRE 16 -1 (-2850 3700)(-2675 3700);
WIRE 16 -1 (-2675 2650)(-3775 2650);
FORCEPROP 2 LAST SIG_NAME M_C_CPU1_CLK_DP<1>
J 0
(-3687 2659);
DISPLAY 0.680851 (-3687 2659);
PAINT WHITE (-3687 2659);
WIRE 16 -1 (-2675 2600)(-3775 2600);
FORCEPROP 2 LAST SIG_NAME M_C_CPU1_CLK_DN<1>
J 0
(-3687 2609);
DISPLAY 0.680851 (-3687 2609);
PAINT WHITE (-3687 2609);
WIRE 16 -1 (-1475 2250)(-1300 2250);
WIRE 16 -1 (-1475 2200)(-1300 2200);
WIRE 16 -1 (3425 3750)(3175 3750);
WIRE 16 -1 (3175 3700)(3175 3750);
WIRE 16 -1 (3175 3700)(3425 3700);
WIRE 16 -1 (3175 3650)(3175 3700);
WIRE 16 -1 (3425 3650)(3175 3650);
WIRE 16 -1 (3175 3600)(3175 3650);
WIRE 16 -1 (3175 3600)(3425 3600);
WIRE 16 -1 (3175 3550)(3425 3550);
WIRE 16 -1 (3175 3550)(3175 3600);
WIRE 16 -1 (3175 3500)(3175 3550);
WIRE 16 -1 (3175 3500)(3425 3500);
WIRE 16 -1 (3175 3450)(3175 3500);
WIRE 16 -1 (3175 3450)(3425 3450);
WIRE 16 -1 (3175 3400)(3175 3450);
WIRE 16 -1 (3175 3400)(3425 3400);
WIRE 16 -1 (3175 3350)(3175 3400);
WIRE 16 -1 (3175 3350)(3425 3350);
WIRE 16 -1 (3175 3300)(3175 3350);
WIRE 16 -1 (3175 3300)(3425 3300);
WIRE 16 -1 (3175 3250)(3175 3300);
WIRE 16 -1 (3175 3250)(3425 3250);
WIRE 16 -1 (3175 3200)(3175 3250);
WIRE 16 -1 (3175 3200)(3425 3200);
WIRE 16 -1 (3175 3150)(3175 3200);
WIRE 16 -1 (3425 3150)(3175 3150);
WIRE 16 -1 (3175 3100)(3175 3150);
WIRE 16 -1 (3175 3100)(3425 3100);
WIRE 16 -1 (3175 3050)(3425 3050);
WIRE 16 -1 (3175 3050)(3175 3100);
WIRE 16 -1 (3175 3000)(3175 3050);
WIRE 16 -1 (3175 3000)(3425 3000);
WIRE 16 -1 (3175 2950)(3175 3000);
WIRE 16 -1 (3175 2950)(3425 2950);
WIRE 16 -1 (3175 2900)(3175 2950);
WIRE 16 -1 (3175 2900)(3425 2900);
WIRE 16 -1 (3175 2850)(3175 2900);
WIRE 16 -1 (3175 2850)(3425 2850);
WIRE 16 -1 (3175 2800)(3175 2850);
WIRE 16 -1 (3175 2800)(3425 2800);
WIRE 16 -1 (3175 2750)(3175 2800);
WIRE 16 -1 (3175 2750)(3425 2750);
WIRE 16 -1 (3175 2700)(3175 2750);
WIRE 16 -1 (3175 2700)(3425 2700);
WIRE 16 -1 (3175 2650)(3175 2700);
WIRE 16 -1 (3425 2650)(3175 2650);
WIRE 16 -1 (3175 2600)(3175 2650);
WIRE 16 -1 (3175 2600)(3425 2600);
WIRE 16 -1 (3175 2550)(3425 2550);
WIRE 16 -1 (3175 2550)(3175 2600);
WIRE 16 -1 (3175 2500)(3175 2550);
WIRE 16 -1 (3175 2500)(3425 2500);
WIRE 16 -1 (3175 2450)(3175 2500);
WIRE 16 -1 (3175 2450)(3425 2450);
WIRE 16 -1 (3175 2400)(3175 2450);
WIRE 16 -1 (3175 2400)(3425 2400);
WIRE 16 -1 (3175 2350)(3175 2400);
WIRE 16 -1 (3175 2350)(3425 2350);
WIRE 16 -1 (3175 2300)(3175 2350);
WIRE 16 -1 (3175 2300)(3425 2300);
WIRE 16 -1 (3175 2250)(3175 2300);
WIRE 16 -1 (3175 2250)(3425 2250);
WIRE 16 -1 (3175 2200)(3175 2250);
WIRE 16 -1 (3175 2200)(3425 2200);
WIRE 16 -1 (3175 2150)(3175 2200);
WIRE 16 -1 (3425 2150)(3175 2150);
WIRE 16 -1 (3175 2100)(3175 2150);
WIRE 16 -1 (3175 2100)(3425 2100);
WIRE 16 -1 (3175 2050)(3175 2100);
WIRE 16 -1 (3175 2050)(3425 2050);
WIRE 16 -1 (3175 2000)(3425 2000);
WIRE 16 -1 (3175 2000)(3175 2050);
WIRE 16 -1 (3175 1950)(3175 2000);
WIRE 16 -1 (3175 1950)(3425 1950);
WIRE 16 -1 (3175 1900)(3175 1950);
WIRE 16 -1 (3175 1900)(3425 1900);
WIRE 16 -1 (3175 1850)(3175 1900);
WIRE 16 -1 (3175 1850)(3425 1850);
WIRE 16 -1 (3175 1800)(3175 1850);
WIRE 16 -1 (3175 1800)(3425 1800);
WIRE 16 -1 (3175 1750)(3175 1800);
WIRE 16 -1 (3175 1750)(3425 1750);
WIRE 16 -1 (3175 1700)(3175 1750);
WIRE 16 -1 (3175 1700)(3425 1700);
WIRE 16 -1 (3175 1650)(3175 1700);
WIRE 16 -1 (3425 1650)(3175 1650);
WIRE 16 -1 (3175 1600)(3175 1650);
WIRE 16 -1 (3175 1600)(3425 1600);
WIRE 16 -1 (3175 1550)(3175 1600);
WIRE 16 -1 (3175 1550)(3425 1550);
WIRE 16 -1 (3175 1500)(3425 1500);
WIRE 16 -1 (3175 1500)(3175 1550);
WIRE 16 -1 (3175 1450)(3175 1500);
WIRE 16 -1 (3175 1450)(3425 1450);
WIRE 16 -1 (3175 1400)(3175 1450);
WIRE 16 -1 (3175 1400)(3425 1400);
WIRE 16 -1 (3175 1350)(3175 1400);
WIRE 16 -1 (3175 1350)(3425 1350);
WIRE 16 -1 (3175 1300)(3175 1350);
WIRE 16 -1 (3175 1300)(3425 1300);
WIRE 16 -1 (3175 1250)(3175 1300);
WIRE 16 -1 (3175 1250)(3425 1250);
WIRE 16 -1 (3175 1200)(3175 1250);
WIRE 16 -1 (3175 1200)(3425 1200);
WIRE 16 -1 (3175 1150)(3175 1200);
WIRE 16 -1 (3425 1150)(3175 1150);
WIRE 16 -1 (3175 1100)(3175 1150);
WIRE 16 -1 (3175 1100)(3425 1100);
WIRE 16 -1 (3175 1050)(3175 1100);
WIRE 16 -1 (3175 1050)(3425 1050);
WIRE 16 -1 (3175 1000)(3425 1000);
WIRE 16 -1 (3175 1000)(3175 1050);
WIRE 16 -1 (3175 950)(3175 1000);
WIRE 16 -1 (3175 950)(3425 950);
WIRE 16 -1 (3175 900)(3175 950);
WIRE 16 -1 (3175 900)(3425 900);
WIRE 16 -1 (3175 850)(3175 900);
WIRE 16 -1 (3175 850)(3425 850);
WIRE 16 -1 (3175 800)(3175 850);
WIRE 16 -1 (3175 800)(3425 800);
WIRE 16 -1 (3175 750)(3175 800);
WIRE 16 -1 (3175 750)(3425 750);
WIRE 16 -1 (3175 700)(3175 750);
WIRE 16 -1 (3175 700)(3425 700);
WIRE 16 -1 (3175 650)(3175 700);
WIRE 16 -1 (3175 650)(3425 650);
WIRE 16 -1 (4625 600)(4875 600);
WIRE 16 -1 (4625 650)(4875 650);
WIRE 16 -1 (4875 650)(4875 600);
WIRE 16 -1 (4625 750)(4875 750);
WIRE 16 -1 (4875 750)(4875 650);
WIRE 16 -1 (4625 800)(4875 800);
WIRE 16 -1 (4875 800)(4875 750);
WIRE 16 -1 (4625 850)(4875 850);
WIRE 16 -1 (4875 800)(4875 850);
WIRE 16 -1 (4625 900)(4875 900);
WIRE 16 -1 (4875 900)(4875 850);
WIRE 16 -1 (4625 950)(4875 950);
WIRE 16 -1 (4875 950)(4875 900);
WIRE 16 -1 (4625 1000)(4875 1000);
WIRE 16 -1 (4875 1000)(4875 950);
WIRE 16 -1 (4875 1050)(4875 1000);
WIRE 16 -1 (4625 1050)(4875 1050);
WIRE 16 -1 (4625 1100)(4875 1100);
WIRE 16 -1 (4875 1100)(4875 1050);
WIRE 16 -1 (4625 1150)(4875 1150);
WIRE 16 -1 (4875 1150)(4875 1100);
WIRE 16 -1 (4875 1200)(4625 1200);
WIRE 16 -1 (4875 1200)(4875 1150);
WIRE 16 -1 (4875 1250)(4625 1250);
WIRE 16 -1 (4875 1250)(4875 1200);
WIRE 16 -1 (4875 1300)(4625 1300);
WIRE 16 -1 (4875 1300)(4875 1250);
WIRE 16 -1 (4625 1350)(4875 1350);
WIRE 16 -1 (4875 1300)(4875 1350);
WIRE 16 -1 (4875 1400)(4625 1400);
WIRE 16 -1 (4875 1350)(4875 1400);
WIRE 16 -1 (4875 1450)(4625 1450);
WIRE 16 -1 (4875 1450)(4875 1400);
WIRE 16 -1 (4875 1500)(4625 1500);
WIRE 16 -1 (4875 1500)(4875 1450);
WIRE 16 -1 (4875 1550)(4875 1500);
WIRE 16 -1 (4875 1550)(4625 1550);
WIRE 16 -1 (4625 1600)(4875 1600);
WIRE 16 -1 (4875 1600)(4875 1550);
WIRE 16 -1 (4625 1650)(4875 1650);
WIRE 16 -1 (4875 1650)(4875 1600);
WIRE 16 -1 (4625 1700)(4875 1700);
WIRE 16 -1 (4875 1650)(4875 1700);
WIRE 16 -1 (4625 1750)(4875 1750);
WIRE 16 -1 (4875 1750)(4875 1700);
WIRE 16 -1 (4625 1800)(4875 1800);
WIRE 16 -1 (4875 1800)(4875 1750);
WIRE 16 -1 (4625 1850)(4875 1850);
WIRE 16 -1 (4875 1850)(4875 1800);
WIRE 16 -1 (4625 1900)(4875 1900);
WIRE 16 -1 (4875 1900)(4875 1850);
WIRE 16 -1 (4625 1950)(4875 1950);
WIRE 16 -1 (4875 1950)(4875 1900);
WIRE 16 -1 (4875 2000)(4625 2000);
WIRE 16 -1 (4875 2000)(4875 1950);
WIRE 16 -1 (4875 2050)(4875 2000);
WIRE 16 -1 (4875 2050)(4625 2050);
WIRE 16 -1 (4625 2100)(4875 2100);
WIRE 16 -1 (4875 2100)(4875 2050);
WIRE 16 -1 (4625 2150)(4875 2150);
WIRE 16 -1 (4875 2150)(4875 2100);
WIRE 16 -1 (4625 2200)(4875 2200);
WIRE 16 -1 (4875 2150)(4875 2200);
WIRE 16 -1 (4625 2250)(4875 2250);
WIRE 16 -1 (4875 2250)(4875 2200);
WIRE 16 -1 (4625 2300)(4875 2300);
WIRE 16 -1 (4875 2300)(4875 2250);
WIRE 16 -1 (4625 2350)(4875 2350);
WIRE 16 -1 (4875 2350)(4875 2300);
WIRE 16 -1 (4625 2400)(4875 2400);
WIRE 16 -1 (4875 2400)(4875 2350);
WIRE 16 -1 (4625 2450)(4875 2450);
WIRE 16 -1 (4875 2450)(4875 2400);
WIRE 16 -1 (4875 2500)(4625 2500);
WIRE 16 -1 (4875 2500)(4875 2450);
WIRE 16 -1 (4875 2550)(4625 2550);
WIRE 16 -1 (4875 2550)(4875 2500);
WIRE 16 -1 (4875 2600)(4875 2550);
WIRE 16 -1 (4625 2600)(4875 2600);
WIRE 16 -1 (4625 2650)(4875 2650);
WIRE 16 -1 (4875 2650)(4875 2600);
WIRE 16 -1 (4625 2700)(4875 2700);
WIRE 16 -1 (4875 2650)(4875 2700);
WIRE 16 -1 (4625 2750)(4875 2750);
WIRE 16 -1 (4875 2750)(4875 2700);
WIRE 16 -1 (4625 2800)(4875 2800);
WIRE 16 -1 (4875 2800)(4875 2750);
WIRE 16 -1 (4625 2850)(4875 2850);
WIRE 16 -1 (4875 2850)(4875 2800);
WIRE 16 -1 (4625 2900)(4875 2900);
WIRE 16 -1 (4875 2900)(4875 2850);
WIRE 16 -1 (4625 2950)(4875 2950);
WIRE 16 -1 (4875 2950)(4875 2900);
WIRE 16 -1 (4875 3000)(4625 3000);
WIRE 16 -1 (4875 3000)(4875 2950);
WIRE 16 -1 (4875 3050)(4625 3050);
WIRE 16 -1 (4875 3050)(4875 3000);
WIRE 16 -1 (4875 3100)(4875 3050);
WIRE 16 -1 (4625 3100)(4875 3100);
WIRE 16 -1 (4625 3150)(4875 3150);
WIRE 16 -1 (4875 3150)(4875 3100);
WIRE 16 -1 (4625 3200)(4875 3200);
WIRE 16 -1 (4875 3150)(4875 3200);
WIRE 16 -1 (4625 3250)(4875 3250);
WIRE 16 -1 (4875 3250)(4875 3200);
WIRE 16 -1 (4625 3300)(4875 3300);
WIRE 16 -1 (4875 3300)(4875 3250);
WIRE 16 -1 (4625 3350)(4875 3350);
WIRE 16 -1 (4875 3350)(4875 3300);
WIRE 16 -1 (4625 3400)(4875 3400);
WIRE 16 -1 (4875 3400)(4875 3350);
WIRE 16 -1 (4625 3450)(4875 3450);
WIRE 16 -1 (4875 3450)(4875 3400);
WIRE 16 -1 (4625 3500)(4875 3500);
WIRE 16 -1 (4875 3500)(4875 3450);
WIRE 16 -1 (4625 3550)(4875 3550);
WIRE 16 -1 (4875 3550)(4875 3500);
WIRE 16 -1 (4875 3600)(4875 3550);
WIRE 16 -1 (4625 3600)(4875 3600);
WIRE 16 -1 (4625 3650)(4875 3650);
WIRE 16 -1 (4875 3650)(4875 3600);
WIRE 16 -1 (4625 3700)(4875 3700);
WIRE 16 -1 (4875 3700)(4875 3650);
WIRE 16 -1 (4625 3750)(4875 3750);
WIRE 16 -1 (4875 3750)(4875 3700);
WIRE 16 -1 (4625 3800)(4875 3800);
WIRE 16 -1 (4875 3800)(4875 3750);
WIRE 16 -1 (4625 3850)(4875 3850);
WIRE 16 -1 (4875 3850)(4875 3800);
WIRE 16 -1 (4875 3900)(4875 3850);
WIRE 16 -1 (4625 3900)(4875 3900);
WIRE 16 -1 (-1475 1900)(-1300 1900);
WIRE 16 -1 (-2675 650)(-3775 650);
FORCEPROP 2 LAST SIG_NAME TP_CHC_CPU1_DIMM2_FRU_0
J 0
(-3687 659);
DISPLAY 0.680851 (-3687 659);
PAINT WHITE (-3687 659);
WIRE 16 -1 (-2675 700)(-3775 700);
FORCEPROP 2 LAST SIG_NAME TP_CHC_CPU1_DIMM2_FRU_1
J 0
(-3687 709);
DISPLAY 0.680851 (-3687 709);
PAINT WHITE (-3687 709);
WIRE 16 -1 (-2675 750)(-3775 750);
FORCEPROP 2 LAST SIG_NAME TP_CHC_CPU1_DIMM2_FRU_2
J 0
(-3687 759);
DISPLAY 0.680851 (-3687 759);
PAINT WHITE (-3687 759);
WIRE 16 -1 (-2675 800)(-3775 800);
FORCEPROP 2 LAST SIG_NAME TP_CHC_CPU1_DIMM2_FRU_3
J 0
(-3687 809);
DISPLAY 0.680851 (-3687 809);
PAINT WHITE (-3687 809);
WIRE 16 -1 (-2675 850)(-3775 850);
FORCEPROP 2 LAST SIG_NAME TP_CHC_CPU1_DIMM2_FRU_4
J 0
(-3687 859);
DISPLAY 0.680851 (-3687 859);
PAINT WHITE (-3687 859);
WIRE 16 -1 (-2675 900)(-3775 900);
FORCEPROP 2 LAST SIG_NAME TP_CHC_CPU1_DIMM2_FRU_5
J 0
(-3687 909);
DISPLAY 0.680851 (-3687 909);
PAINT WHITE (-3687 909);
WIRE 16 -1 (-2675 3050)(-3775 3050);
FORCEPROP 2 LAST SIG_NAME M_C_CPU1_SB_PAR
J 0
(-3687 3059);
DISPLAY 0.680851 (-3687 3059);
PAINT WHITE (-3687 3059);
WIRE 16 -1 (-2675 3100)(-3775 3100);
FORCEPROP 2 LAST SIG_NAME M_C_CPU1_SA_PAR
J 0
(-3687 3109);
DISPLAY 0.680851 (-3687 3109);
PAINT WHITE (-3687 3109);
WIRE 16 -1 (-2675 450)(-3775 450);
FORCEPROP 2 LAST SIG_NAME M_C_CPU1_SB_RSP<1>
J 0
(-3687 459);
DISPLAY 0.680851 (-3687 459);
PAINT WHITE (-3687 459);
WIRE 16 -1 (-2675 500)(-3775 500);
FORCEPROP 2 LAST SIG_NAME M_C_CPU1_SA_RSP<1>
J 0
(-3687 509);
DISPLAY 0.680851 (-3687 509);
PAINT WHITE (-3687 509);
WIRE 16 -1 (-1475 700)(-1300 700);
WIRE 16 -1 (-1475 750)(-1300 750);
WIRE 16 -1 (-1475 800)(-1300 800);
WIRE 16 -1 (-1475 850)(-1300 850);
WIRE 16 -1 (-1475 950)(-1300 950);
WIRE 16 -1 (-1475 1000)(-1300 1000);
WIRE 16 -1 (-1475 1050)(-1300 1050);
WIRE 16 -1 (-1475 1100)(-1300 1100);
WIRE 16 -1 (-1475 1150)(-1300 1150);
WIRE 16 -1 (-1475 1250)(-1300 1250);
WIRE 16 -1 (-1475 1300)(-1300 1300);
WIRE 16 -1 (-1475 1350)(-1300 1350);
WIRE 16 -1 (-1475 1400)(-1300 1400);
WIRE 16 -1 (-1475 1450)(-1300 1450);
WIRE 16 -1 (-1475 1500)(-1300 1500);
WIRE 16 -1 (-1475 1550)(-1300 1550);
WIRE 16 -1 (-1475 1650)(-1300 1650);
WIRE 16 -1 (-1475 1700)(-1300 1700);
WIRE 16 -1 (-1475 1750)(-1300 1750);
WIRE 16 -1 (-1475 1800)(-1300 1800);
WIRE 16 -1 (-1475 1850)(-1300 1850);
WIRE 16 -1 (-1475 1950)(-1300 1950);
WIRE 16 -1 (-1475 2000)(-1300 2000);
WIRE 16 -1 (-1475 2050)(-1300 2050);
WIRE 16 -1 (-1475 2100)(-1300 2100);
WIRE 16 -1 (-1475 2150)(-1300 2150);
WIRE 16 -1 (-1475 2350)(-1300 2350);
WIRE 16 -1 (-1475 2400)(-1300 2400);
WIRE 16 -1 (-1475 2450)(-1300 2450);
WIRE 16 -1 (-1475 2500)(-1300 2500);
WIRE 16 -1 (-1475 2550)(-1300 2550);
WIRE 16 -1 (-1475 2600)(-1300 2600);
WIRE 16 -1 (-1475 2650)(-1300 2650);
WIRE 16 -1 (-1475 2700)(-1300 2700);
WIRE 16 -1 (-1475 2750)(-1300 2750);
WIRE 16 -1 (-1475 2800)(-1300 2800);
WIRE 16 -1 (-1475 2850)(-1300 2850);
WIRE 16 -1 (-1475 2900)(-1300 2900);
WIRE 16 -1 (-1475 2950)(-1300 2950);
WIRE 16 -1 (-1475 3000)(-1300 3000);
WIRE 16 -1 (-1475 3050)(-1300 3050);
WIRE 16 -1 (-1475 3100)(-1300 3100);
WIRE 16 -1 (-1475 3150)(-1300 3150);
WIRE 16 -1 (-1475 3200)(-1300 3200);
WIRE 16 -1 (-1475 3250)(-1300 3250);
WIRE 16 -1 (-1475 3300)(-1300 3300);
WIRE 16 -1 (-1475 3350)(-1300 3350);
WIRE 16 -1 (-1475 3400)(-1300 3400);
WIRE 16 -1 (-1475 3450)(-1300 3450);
WIRE 16 -1 (-1475 3500)(-1300 3500);
WIRE 16 -1 (-1475 3550)(-1300 3550);
WIRE 16 -1 (-1475 3600)(-1300 3600);
WIRE 16 -1 (-1475 3650)(-1300 3650);
WIRE 16 -1 (-1475 3700)(-1300 3700);
WIRE 16 -1 (-1475 3800)(-1300 3800);
WIRE 16 -1 (-1475 3850)(-1300 3850);
WIRE 16 -1 (-2675 2950)(-3775 2950);
FORCEPROP 2 LAST SIG_NAME M_C_CPU1_SA_CS_N<3>
J 0
(-3687 2959);
DISPLAY 0.680851 (-3687 2959);
PAINT WHITE (-3687 2959);
WIRE 16 -1 (-2850 1750)(-2675 1750);
WIRE 16 -1 (-2850 1800)(-2675 1800);
WIRE 16 -1 (-2850 1850)(-2675 1850);
WIRE 16 -1 (-2850 1950)(-2675 1950);
WIRE 16 -1 (-2850 2000)(-2675 2000);
WIRE 16 -1 (-2850 2150)(-2675 2150);
WIRE 16 -1 (-2850 2250)(-2675 2250);
WIRE 16 -1 (-2850 2300)(-2675 2300);
WIRE 16 -1 (-2850 2400)(-2675 2400);
WIRE 16 -1 (-2850 2450)(-2675 2450);
WIRE 16 -1 (-2850 3500)(-2675 3500);
WIRE 16 -1 (-2850 3900)(-2675 3900);
WIRE 16 -1 (-2850 3450)(-2675 3450);
WIRE 16 -1 (-2850 3850)(-2675 3850);
WIRE 16 -1 (-2850 3400)(-2675 3400);
WIRE 16 -1 (-2850 3800)(-2675 3800);
WIRE 16 -1 (-2850 3350)(-2675 3350);
WIRE 16 -1 (-2850 3750)(-2675 3750);
WIRE 16 -1 (-2850 3300)(-2675 3300);
WIRE 16 -1 (-2850 3250)(-2675 3250);
WIRE 16 -1 (-2850 3650)(-2675 3650);
WIRE 16 -1 (-2850 3200)(-2675 3200);
WIRE 16 -1 (-2850 3600)(-2675 3600);
WIRE 16 -1 (-2850 2050)(-2675 2050);
WIRE 16 -1 (-2850 2200)(-2675 2200);
WIRE 16 -1 (-2850 2350)(-2675 2350);
WIRE 16 -1 (-2850 2500)(-2675 2500);
WIRE 16 -1 (-1475 3900)(-1300 3900);
WIRE 16 -1 (-2675 -50)(-3775 -50);
FORCEPROP 2 LAST SIG_NAME PD_CHC_CPU1_DIMM2_SAA
J 0
(-3687 -41);
DISPLAY 0.680851 (-3687 -41);
PAINT WHITE (-3687 -41);
WIRE 16 -1 (-2675 -150)(-2675 -50);
WIRE 16 -1 (1475 250)(1475 125);
WIRE 16 -1 (2100 250)(1475 250);
WIRE 16 -1 (2100 125)(2100 250);
WIRE 16 -1 (1475 -225)(1475 -75);
WIRE 16 -1 (2100 -225)(1475 -225);
WIRE 16 -1 (2100 -225)(2100 -75);
DOT 1 (3175 2300);
DOT 1 (3175 1500);
DOT 1 (3175 1550);
DOT 1 (3175 2350);
DOT 1 (4875 550);
DOT 1 (4875 600);
DOT 1 (4875 650);
DOT 1 (4875 3850);
DOT 1 (4875 3800);
DOT 1 (4875 3750);
DOT 1 (4875 3700);
DOT 1 (4875 3650);
DOT 1 (4875 3600);
DOT 1 (4875 3550);
DOT 1 (4875 3500);
DOT 1 (4875 3450);
DOT 1 (4875 3400);
DOT 1 (4875 3350);
DOT 1 (4875 3300);
DOT 1 (4875 3250);
DOT 1 (4875 3200);
DOT 1 (4875 3150);
DOT 1 (4875 3100);
DOT 1 (4875 3050);
DOT 1 (4875 3000);
DOT 1 (4875 2950);
DOT 1 (4875 2900);
DOT 1 (4875 2850);
DOT 1 (4875 2800);
DOT 1 (4875 2750);
DOT 1 (4875 2700);
DOT 1 (4875 2650);
DOT 1 (4875 2600);
DOT 1 (4875 2550);
DOT 1 (4875 2500);
DOT 1 (4875 2450);
DOT 1 (4875 2400);
DOT 1 (4875 2350);
DOT 1 (4875 2300);
DOT 1 (4875 2250);
DOT 1 (4875 2200);
DOT 1 (4875 2150);
DOT 1 (4875 2100);
DOT 1 (4875 2050);
DOT 1 (4875 2000);
DOT 1 (4875 1950);
DOT 1 (4875 1900);
DOT 1 (4875 1850);
DOT 1 (4875 1800);
DOT 1 (4875 1750);
DOT 1 (4875 1700);
DOT 1 (4875 1650);
DOT 1 (4875 1600);
DOT 1 (4875 1550);
DOT 1 (4875 1500);
DOT 1 (4875 1450);
DOT 1 (4875 1400);
DOT 1 (4875 1350);
DOT 1 (4875 1300);
DOT 1 (4875 1250);
DOT 1 (4875 1200);
DOT 1 (4875 1150);
DOT 1 (4875 1100);
DOT 1 (4875 1050);
DOT 1 (4875 1000);
DOT 1 (4875 950);
DOT 1 (4875 900);
DOT 1 (4875 850);
DOT 1 (4875 800);
DOT 1 (4875 750);
DOT 1 (3175 3900);
DOT 1 (3175 3850);
DOT 1 (3175 3700);
DOT 1 (3175 3650);
DOT 1 (3175 3600);
DOT 1 (3175 3550);
DOT 1 (3175 3500);
DOT 1 (3175 3450);
DOT 1 (3175 3400);
DOT 1 (3175 3350);
DOT 1 (3175 3300);
DOT 1 (3175 3250);
DOT 1 (3175 3150);
DOT 1 (3175 3200);
DOT 1 (3175 3100);
DOT 1 (3175 3050);
DOT 1 (3175 3000);
DOT 1 (3175 2950);
DOT 1 (3175 2900);
DOT 1 (3175 2850);
DOT 1 (3175 2800);
DOT 1 (3175 2750);
DOT 1 (3175 2700);
DOT 1 (3175 2650);
DOT 1 (3175 2600);
DOT 1 (3175 2550);
DOT 1 (3175 2500);
DOT 1 (3175 2450);
DOT 1 (3175 2400);
DOT 1 (3175 2250);
DOT 1 (3175 2200);
DOT 1 (3175 2150);
DOT 1 (3175 2100);
DOT 1 (3175 2050);
DOT 1 (3175 2000);
DOT 1 (3175 1950);
DOT 1 (3175 1900);
DOT 1 (3175 1850);
DOT 1 (3175 1800);
DOT 1 (3175 1750);
DOT 1 (3175 1700);
DOT 1 (3175 1650);
DOT 1 (3175 1600);
DOT 1 (3175 1450);
DOT 1 (3175 1400);
DOT 1 (3175 1350);
DOT 1 (3175 1300);
DOT 1 (3175 1250);
DOT 1 (3175 1200);
DOT 1 (3175 1150);
DOT 1 (3175 1100);
DOT 1 (3175 1050);
DOT 1 (3175 1000);
DOT 1 (3175 950);
DOT 1 (3175 900);
DOT 1 (3175 850);
DOT 1 (3175 800);
DOT 1 (3175 750);
DOT 1 (3175 700);
DOT 1 (3175 650);
DOT 1 (1475 250);
DOT 1 (2100 -225);
FORCENOTE
20210728 MODIFY FOR GT
(-4150 4575) 0;
DISPLAY LEFT (-4150 4575);
DISPLAY 2.510638 (-4150 4575);
PAINT PINK (-4150 4575);
QUIT
